FILE_TYPE = MACRO_DRAWING;
SET COLOR_WIRE YELLOW;
SET COLOR_PROP ORANGE;
SET COLOR_DOT WHITE;
SET COLOR_ARC YELLOW;
SET COLOR_BODY GREEN;
SET COLOR_NOTE PURPLE;
SET PROP_DISPLAY VALUE;
SET PAGE_NUMBER P136;
FORCEADD Q_RES..1
R 2
(-6075 5725);
FORCEPROP 1 LAST LOCATION R427
J 2
(-6175 5725);
DISPLAY 0.489362 (-6175 5725);
PAINT SKYBLUE (-6175 5725);
FORCEPROP 0 LAST $SEC 1
J 2
(-5800 5775);
DISPLAY 0.680851 (-5800 5775);
PAINT MONO (-5800 5775);
DISPLAY INVISIBLE (-5800 5775);
FORCEPROP 0 LAST CDS_SEC 1
J 2
(-5800 5775);
DISPLAY 1.021277 (-5800 5775);
DISPLAY INVISIBLE (-5800 5775);
FORCEPROP 1 LASTPIN (-5975 5725) $PN 1
J 2
(-5987 5737);
DISPLAY 0.489362 (-5987 5737);
PAINT MONO (-5987 5737);
FORCEPROP 1 LASTPIN (-6175 5725) $PN 2
J 2
(-6137 5737);
DISPLAY 0.489362 (-6137 5737);
PAINT MONO (-6137 5737);
FORCEPROP 1 LAST VALUE 0
J 0
(-5975 5725);
DISPLAY 0.489362 (-5975 5725);
PAINT SKYBLUE (-5975 5725);
FORCEPROP 2 LAST CDS_LIB pure_quanta
J 2
(-6075 5725);
DISPLAY INVISIBLE (-6075 5725);
FORCEPROP 1 LAST PATH I100
J 2
(-6025 5875);
DISPLAY 0.978723 (-6025 5875);
PAINT WHITE (-6025 5875);
DISPLAY INVISIBLE (-6025 5875);
FORCEPROP 1 LAST WATTAGE 1/16W
J 0
(-6475 5650);
DISPLAY 0.489362 (-6475 5650);
PAINT SKYBLUE (-6475 5650);
DISPLAY INVISIBLE (-6475 5650);
FORCEPROP 1 LAST MATERIAL CHIP
J 2
(-6500 5650);
DISPLAY 0.489362 (-6500 5650);
PAINT SKYBLUE (-6500 5650);
DISPLAY INVISIBLE (-6500 5650);
FORCEPROP 1 LAST TOLERANCE 5%
J 2
(-6050 5650);
DISPLAY 0.489362 (-6050 5650);
PAINT SKYBLUE (-6050 5650);
DISPLAY INVISIBLE (-6050 5650);
FORCEPROP 1 LAST PART_NUMBER CS00002JB38
J 2
(-6100 5775);
DISPLAY 0.489362 (-6100 5775);
PAINT SKYBLUE (-6100 5775);
DISPLAY INVISIBLE (-6100 5775);
FORCEPROP 1 LAST PACK_TYPE 0402LF
J 2
(-6125 5650);
DISPLAY 0.489362 (-6125 5650);
PAINT SKYBLUE (-6125 5650);
DISPLAY INVISIBLE (-6125 5650);
FORCEADD OFFPAGE..1
(-7125 5775);
FORCEPROP 2 LAST $XR0 28 
J 0
(-7376 5775);
DISPLAY 0.638298 (-7376 5775);
PAINT MONO (-7376 5775);
FORCEPROP 1 LAST OFFPAGE TRUE
J 0
(-6800 5650);
DISPLAY 0.872340 (-6800 5650);
PAINT GREEN (-6800 5650);
DISPLAY INVISIBLE (-6800 5650);
FORCEPROP 1 LAST COMMENT_BODY TRUE
J 0
(-7000 5675);
DISPLAY 0.872340 (-7000 5675);
PAINT GREEN (-7000 5675);
DISPLAY INVISIBLE (-7000 5675);
FORCEPROP 2 LAST PATH I101
J 0
(-7075 5850);
DISPLAY 1.021277 (-7075 5850);
DISPLAY INVISIBLE (-7075 5850);
FORCEPROP 2 LAST CDS_LIB standard
J 0
(-7125 5775);
DISPLAY INVISIBLE (-7125 5775);
FORCEADD OFFPAGE..3
R 2
(-7125 5725);
FORCEPROP 2 LAST $XR0 28 
J 0
(-7404 5725);
DISPLAY 0.638298 (-7404 5725);
PAINT MONO (-7404 5725);
FORCEPROP 2 LAST PATH I102
J 0
(-7075 5800);
DISPLAY 1.021277 (-7075 5800);
DISPLAY INVISIBLE (-7075 5800);
FORCEPROP 1 LAST COMMENT_BODY TRUE
J 2
(-7075 5625);
DISPLAY 0.872340 (-7075 5625);
PAINT GREEN (-7075 5625);
DISPLAY INVISIBLE (-7075 5625);
FORCEPROP 1 LAST OFFPAGE TRUE
J 2
(-7450 5600);
DISPLAY 0.872340 (-7450 5600);
PAINT GREEN (-7450 5600);
DISPLAY INVISIBLE (-7450 5600);
FORCEPROP 2 LAST CDS_LIB standard
J 0
(-7125 5725);
DISPLAY INVISIBLE (-7125 5725);
FORCEADD Q_RES..1
R 2
(-6050 4375);
FORCEPROP 1 LAST LOCATION R428
J 2
(-6150 4375);
DISPLAY 0.489362 (-6150 4375);
PAINT SKYBLUE (-6150 4375);
FORCEPROP 0 LAST $SEC 1
J 2
(-5775 4425);
DISPLAY 0.680851 (-5775 4425);
PAINT MONO (-5775 4425);
DISPLAY INVISIBLE (-5775 4425);
FORCEPROP 0 LAST CDS_SEC 1
J 2
(-5775 4425);
DISPLAY 1.021277 (-5775 4425);
DISPLAY INVISIBLE (-5775 4425);
FORCEPROP 1 LASTPIN (-5950 4375) $PN 1
J 2
(-5962 4387);
DISPLAY 0.489362 (-5962 4387);
PAINT MONO (-5962 4387);
FORCEPROP 1 LASTPIN (-6150 4375) $PN 2
J 2
(-6112 4387);
DISPLAY 0.489362 (-6112 4387);
PAINT MONO (-6112 4387);
FORCEPROP 1 LAST VALUE 0
J 0
(-5950 4375);
DISPLAY 0.489362 (-5950 4375);
PAINT SKYBLUE (-5950 4375);
FORCEPROP 2 LAST CDS_LIB pure_quanta
J 2
(-6050 4375);
DISPLAY INVISIBLE (-6050 4375);
FORCEPROP 1 LAST PATH I103
J 2
(-6000 4525);
DISPLAY 0.978723 (-6000 4525);
PAINT WHITE (-6000 4525);
DISPLAY INVISIBLE (-6000 4525);
FORCEPROP 1 LAST WATTAGE 1/16W
J 0
(-6450 4300);
DISPLAY 0.489362 (-6450 4300);
PAINT SKYBLUE (-6450 4300);
DISPLAY INVISIBLE (-6450 4300);
FORCEPROP 1 LAST MATERIAL CHIP
J 2
(-6475 4300);
DISPLAY 0.489362 (-6475 4300);
PAINT SKYBLUE (-6475 4300);
DISPLAY INVISIBLE (-6475 4300);
FORCEPROP 1 LAST TOLERANCE 5%
J 2
(-6025 4300);
DISPLAY 0.489362 (-6025 4300);
PAINT SKYBLUE (-6025 4300);
DISPLAY INVISIBLE (-6025 4300);
FORCEPROP 1 LAST PART_NUMBER CS00002JB38
J 2
(-6075 4425);
DISPLAY 0.489362 (-6075 4425);
PAINT SKYBLUE (-6075 4425);
DISPLAY INVISIBLE (-6075 4425);
FORCEPROP 1 LAST PACK_TYPE 0402LF
J 2
(-6100 4300);
DISPLAY 0.489362 (-6100 4300);
PAINT SKYBLUE (-6100 4300);
DISPLAY INVISIBLE (-6100 4300);
FORCEADD Q_RES..1
R 2
(-6050 4325);
FORCEPROP 1 LAST LOCATION R429
J 2
(-6150 4325);
DISPLAY 0.489362 (-6150 4325);
PAINT SKYBLUE (-6150 4325);
FORCEPROP 0 LAST $SEC 1
J 2
(-5775 4375);
DISPLAY 0.680851 (-5775 4375);
PAINT MONO (-5775 4375);
DISPLAY INVISIBLE (-5775 4375);
FORCEPROP 0 LAST CDS_SEC 1
J 2
(-5775 4375);
DISPLAY 1.021277 (-5775 4375);
DISPLAY INVISIBLE (-5775 4375);
FORCEPROP 1 LASTPIN (-5950 4325) $PN 1
J 2
(-5962 4337);
DISPLAY 0.489362 (-5962 4337);
PAINT MONO (-5962 4337);
FORCEPROP 1 LASTPIN (-6150 4325) $PN 2
J 2
(-6112 4337);
DISPLAY 0.489362 (-6112 4337);
PAINT MONO (-6112 4337);
FORCEPROP 1 LAST VALUE 0
J 0
(-5950 4325);
DISPLAY 0.489362 (-5950 4325);
PAINT SKYBLUE (-5950 4325);
FORCEPROP 2 LAST CDS_LIB pure_quanta
J 2
(-6050 4325);
DISPLAY INVISIBLE (-6050 4325);
FORCEPROP 1 LAST PATH I104
J 2
(-6000 4475);
DISPLAY 0.978723 (-6000 4475);
PAINT WHITE (-6000 4475);
DISPLAY INVISIBLE (-6000 4475);
FORCEPROP 1 LAST WATTAGE 1/16W
J 0
(-6450 4250);
DISPLAY 0.489362 (-6450 4250);
PAINT SKYBLUE (-6450 4250);
DISPLAY INVISIBLE (-6450 4250);
FORCEPROP 1 LAST MATERIAL CHIP
J 2
(-6475 4250);
DISPLAY 0.489362 (-6475 4250);
PAINT SKYBLUE (-6475 4250);
DISPLAY INVISIBLE (-6475 4250);
FORCEPROP 1 LAST TOLERANCE 5%
J 2
(-6025 4250);
DISPLAY 0.489362 (-6025 4250);
PAINT SKYBLUE (-6025 4250);
DISPLAY INVISIBLE (-6025 4250);
FORCEPROP 1 LAST PART_NUMBER CS00002JB38
J 2
(-6075 4375);
DISPLAY 0.489362 (-6075 4375);
PAINT SKYBLUE (-6075 4375);
DISPLAY INVISIBLE (-6075 4375);
FORCEPROP 1 LAST PACK_TYPE 0402LF
J 2
(-6100 4250);
DISPLAY 0.489362 (-6100 4250);
PAINT SKYBLUE (-6100 4250);
DISPLAY INVISIBLE (-6100 4250);
FORCEADD OFFPAGE..3
R 2
(-7100 4325);
FORCEPROP 2 LAST $XR0 28 
J 0
(-7349 4325);
DISPLAY 0.638298 (-7349 4325);
PAINT MONO (-7349 4325);
FORCEPROP 2 LAST PATH I105
J 0
(-7050 4400);
DISPLAY 1.021277 (-7050 4400);
DISPLAY INVISIBLE (-7050 4400);
FORCEPROP 1 LAST COMMENT_BODY TRUE
J 2
(-7050 4225);
DISPLAY 0.872340 (-7050 4225);
PAINT GREEN (-7050 4225);
DISPLAY INVISIBLE (-7050 4225);
FORCEPROP 1 LAST OFFPAGE TRUE
J 2
(-7425 4200);
DISPLAY 0.872340 (-7425 4200);
PAINT GREEN (-7425 4200);
DISPLAY INVISIBLE (-7425 4200);
FORCEPROP 2 LAST CDS_LIB standard
J 0
(-7100 4325);
DISPLAY INVISIBLE (-7100 4325);
FORCEADD OFFPAGE..1
(-7100 4375);
FORCEPROP 2 LAST $XR0 28 
J 0
(-7321 4375);
DISPLAY 0.638298 (-7321 4375);
PAINT MONO (-7321 4375);
FORCEPROP 2 LAST PATH I106
J 0
(-7050 4450);
DISPLAY 1.021277 (-7050 4450);
DISPLAY INVISIBLE (-7050 4450);
FORCEPROP 1 LAST COMMENT_BODY TRUE
J 0
(-6975 4275);
DISPLAY 0.872340 (-6975 4275);
PAINT GREEN (-6975 4275);
DISPLAY INVISIBLE (-6975 4275);
FORCEPROP 1 LAST OFFPAGE TRUE
J 0
(-6775 4250);
DISPLAY 0.872340 (-6775 4250);
PAINT GREEN (-6775 4250);
DISPLAY INVISIBLE (-6775 4250);
FORCEPROP 2 LAST CDS_LIB standard
J 0
(-7100 4375);
DISPLAY INVISIBLE (-7100 4375);
FORCEADD Q_RES..1
R 2
(-6050 2800);
FORCEPROP 1 LAST LOCATION R565
J 2
(-6150 2800);
DISPLAY 0.489362 (-6150 2800);
PAINT SKYBLUE (-6150 2800);
FORCEPROP 0 LAST $SEC 1
J 2
(-5775 2850);
DISPLAY 0.680851 (-5775 2850);
PAINT MONO (-5775 2850);
DISPLAY INVISIBLE (-5775 2850);
FORCEPROP 0 LAST CDS_SEC 1
J 2
(-5775 2850);
DISPLAY 1.021277 (-5775 2850);
DISPLAY INVISIBLE (-5775 2850);
FORCEPROP 1 LASTPIN (-5950 2800) $PN 1
J 2
(-5962 2812);
DISPLAY 0.489362 (-5962 2812);
PAINT MONO (-5962 2812);
FORCEPROP 1 LASTPIN (-6150 2800) $PN 2
J 2
(-6112 2812);
DISPLAY 0.489362 (-6112 2812);
PAINT MONO (-6112 2812);
FORCEPROP 1 LAST VALUE 0
J 0
(-5950 2800);
DISPLAY 0.489362 (-5950 2800);
PAINT SKYBLUE (-5950 2800);
FORCEPROP 2 LAST CDS_LIB pure_quanta
J 2
(-6050 2800);
DISPLAY INVISIBLE (-6050 2800);
FORCEPROP 1 LAST PATH I107
J 2
(-6000 2950);
DISPLAY 0.978723 (-6000 2950);
PAINT WHITE (-6000 2950);
DISPLAY INVISIBLE (-6000 2950);
FORCEPROP 1 LAST WATTAGE 1/16W
J 0
(-6450 2725);
DISPLAY 0.489362 (-6450 2725);
PAINT SKYBLUE (-6450 2725);
DISPLAY INVISIBLE (-6450 2725);
FORCEPROP 1 LAST MATERIAL CHIP
J 2
(-6475 2725);
DISPLAY 0.489362 (-6475 2725);
PAINT SKYBLUE (-6475 2725);
DISPLAY INVISIBLE (-6475 2725);
FORCEPROP 1 LAST TOLERANCE 5%
J 2
(-6025 2725);
DISPLAY 0.489362 (-6025 2725);
PAINT SKYBLUE (-6025 2725);
DISPLAY INVISIBLE (-6025 2725);
FORCEPROP 1 LAST PART_NUMBER CS00002JB38
J 2
(-6075 2850);
DISPLAY 0.489362 (-6075 2850);
PAINT SKYBLUE (-6075 2850);
DISPLAY INVISIBLE (-6075 2850);
FORCEPROP 1 LAST PACK_TYPE 0402LF
J 2
(-6100 2725);
DISPLAY 0.489362 (-6100 2725);
PAINT SKYBLUE (-6100 2725);
DISPLAY INVISIBLE (-6100 2725);
FORCEADD Q_RES..1
R 2
(-6050 2850);
FORCEPROP 1 LAST LOCATION R564
J 2
(-6150 2850);
DISPLAY 0.489362 (-6150 2850);
PAINT SKYBLUE (-6150 2850);
FORCEPROP 0 LAST $SEC 1
J 2
(-5775 2900);
DISPLAY 0.680851 (-5775 2900);
PAINT MONO (-5775 2900);
DISPLAY INVISIBLE (-5775 2900);
FORCEPROP 0 LAST CDS_SEC 1
J 2
(-5775 2900);
DISPLAY 1.021277 (-5775 2900);
DISPLAY INVISIBLE (-5775 2900);
FORCEPROP 1 LASTPIN (-5950 2850) $PN 1
J 2
(-5962 2862);
DISPLAY 0.489362 (-5962 2862);
PAINT MONO (-5962 2862);
FORCEPROP 1 LASTPIN (-6150 2850) $PN 2
J 2
(-6112 2862);
DISPLAY 0.489362 (-6112 2862);
PAINT MONO (-6112 2862);
FORCEPROP 1 LAST VALUE 0
J 0
(-5950 2850);
DISPLAY 0.489362 (-5950 2850);
PAINT SKYBLUE (-5950 2850);
FORCEPROP 2 LAST CDS_LIB pure_quanta
J 2
(-6050 2850);
DISPLAY INVISIBLE (-6050 2850);
FORCEPROP 1 LAST PATH I108
J 2
(-6000 3000);
DISPLAY 0.978723 (-6000 3000);
PAINT WHITE (-6000 3000);
DISPLAY INVISIBLE (-6000 3000);
FORCEPROP 1 LAST WATTAGE 1/16W
J 0
(-6450 2775);
DISPLAY 0.489362 (-6450 2775);
PAINT SKYBLUE (-6450 2775);
DISPLAY INVISIBLE (-6450 2775);
FORCEPROP 1 LAST MATERIAL CHIP
J 2
(-6475 2775);
DISPLAY 0.489362 (-6475 2775);
PAINT SKYBLUE (-6475 2775);
DISPLAY INVISIBLE (-6475 2775);
FORCEPROP 1 LAST TOLERANCE 5%
J 2
(-6025 2775);
DISPLAY 0.489362 (-6025 2775);
PAINT SKYBLUE (-6025 2775);
DISPLAY INVISIBLE (-6025 2775);
FORCEPROP 1 LAST PART_NUMBER CS00002JB38
J 2
(-6075 2900);
DISPLAY 0.489362 (-6075 2900);
PAINT SKYBLUE (-6075 2900);
DISPLAY INVISIBLE (-6075 2900);
FORCEPROP 1 LAST PACK_TYPE 0402LF
J 2
(-6100 2775);
DISPLAY 0.489362 (-6100 2775);
PAINT SKYBLUE (-6100 2775);
DISPLAY INVISIBLE (-6100 2775);
FORCEADD OFFPAGE..1
(-7100 2850);
FORCEPROP 2 LAST $XR0 55 
J 0
(-7321 2850);
DISPLAY 0.638298 (-7321 2850);
PAINT MONO (-7321 2850);
FORCEPROP 2 LAST PATH I109
J 0
(-7050 2925);
DISPLAY 1.021277 (-7050 2925);
DISPLAY INVISIBLE (-7050 2925);
FORCEPROP 1 LAST COMMENT_BODY TRUE
J 0
(-6975 2750);
DISPLAY 0.872340 (-6975 2750);
PAINT GREEN (-6975 2750);
DISPLAY INVISIBLE (-6975 2750);
FORCEPROP 1 LAST OFFPAGE TRUE
J 0
(-6775 2725);
DISPLAY 0.872340 (-6775 2725);
PAINT GREEN (-6775 2725);
DISPLAY INVISIBLE (-6775 2725);
FORCEPROP 2 LAST CDS_LIB standard
J 0
(-7100 2850);
DISPLAY INVISIBLE (-7100 2850);
FORCEADD OFFPAGE..3
R 2
(-7100 2800);
FORCEPROP 2 LAST $XR0 55 
J 0
(-7349 2800);
DISPLAY 0.638298 (-7349 2800);
PAINT MONO (-7349 2800);
FORCEPROP 2 LAST PATH I110
J 0
(-7050 2875);
DISPLAY 1.021277 (-7050 2875);
DISPLAY INVISIBLE (-7050 2875);
FORCEPROP 1 LAST COMMENT_BODY TRUE
J 2
(-7050 2700);
DISPLAY 0.872340 (-7050 2700);
PAINT GREEN (-7050 2700);
DISPLAY INVISIBLE (-7050 2700);
FORCEPROP 1 LAST OFFPAGE TRUE
J 2
(-7425 2675);
DISPLAY 0.872340 (-7425 2675);
PAINT GREEN (-7425 2675);
DISPLAY INVISIBLE (-7425 2675);
FORCEPROP 2 LAST CDS_LIB standard
J 0
(-7100 2800);
DISPLAY INVISIBLE (-7100 2800);
FORCEADD Q_RES..1
R 2
(-5975 1400);
FORCEPROP 1 LAST LOCATION R566
J 2
(-6075 1400);
DISPLAY 0.489362 (-6075 1400);
PAINT SKYBLUE (-6075 1400);
FORCEPROP 0 LAST $SEC 1
J 2
(-5700 1450);
DISPLAY 0.680851 (-5700 1450);
PAINT MONO (-5700 1450);
DISPLAY INVISIBLE (-5700 1450);
FORCEPROP 0 LAST CDS_SEC 1
J 2
(-5700 1450);
DISPLAY 1.021277 (-5700 1450);
DISPLAY INVISIBLE (-5700 1450);
FORCEPROP 1 LASTPIN (-5875 1400) $PN 1
J 2
(-5887 1412);
DISPLAY 0.489362 (-5887 1412);
PAINT MONO (-5887 1412);
FORCEPROP 1 LASTPIN (-6075 1400) $PN 2
J 2
(-6037 1412);
DISPLAY 0.489362 (-6037 1412);
PAINT MONO (-6037 1412);
FORCEPROP 1 LAST VALUE 0
J 0
(-5875 1400);
DISPLAY 0.489362 (-5875 1400);
PAINT SKYBLUE (-5875 1400);
FORCEPROP 2 LAST CDS_LIB pure_quanta
J 2
(-5975 1400);
DISPLAY INVISIBLE (-5975 1400);
FORCEPROP 1 LAST PATH I111
J 2
(-5925 1550);
DISPLAY 0.978723 (-5925 1550);
PAINT WHITE (-5925 1550);
DISPLAY INVISIBLE (-5925 1550);
FORCEPROP 1 LAST WATTAGE 1/16W
J 0
(-6375 1325);
DISPLAY 0.489362 (-6375 1325);
PAINT SKYBLUE (-6375 1325);
DISPLAY INVISIBLE (-6375 1325);
FORCEPROP 1 LAST MATERIAL CHIP
J 2
(-6400 1325);
DISPLAY 0.489362 (-6400 1325);
PAINT SKYBLUE (-6400 1325);
DISPLAY INVISIBLE (-6400 1325);
FORCEPROP 1 LAST TOLERANCE 5%
J 2
(-5950 1325);
DISPLAY 0.489362 (-5950 1325);
PAINT SKYBLUE (-5950 1325);
DISPLAY INVISIBLE (-5950 1325);
FORCEPROP 1 LAST PART_NUMBER CS00002JB38
J 2
(-6000 1450);
DISPLAY 0.489362 (-6000 1450);
PAINT SKYBLUE (-6000 1450);
DISPLAY INVISIBLE (-6000 1450);
FORCEPROP 1 LAST PACK_TYPE 0402LF
J 2
(-6025 1325);
DISPLAY 0.489362 (-6025 1325);
PAINT SKYBLUE (-6025 1325);
DISPLAY INVISIBLE (-6025 1325);
FORCEADD Q_RES..1
R 2
(-5975 1350);
FORCEPROP 1 LAST LOCATION R567
J 2
(-6075 1350);
DISPLAY 0.489362 (-6075 1350);
PAINT SKYBLUE (-6075 1350);
FORCEPROP 0 LAST $SEC 1
J 2
(-5700 1400);
DISPLAY 0.680851 (-5700 1400);
PAINT MONO (-5700 1400);
DISPLAY INVISIBLE (-5700 1400);
FORCEPROP 0 LAST CDS_SEC 1
J 2
(-5700 1400);
DISPLAY 1.021277 (-5700 1400);
DISPLAY INVISIBLE (-5700 1400);
FORCEPROP 1 LASTPIN (-5875 1350) $PN 1
J 2
(-5887 1362);
DISPLAY 0.489362 (-5887 1362);
PAINT MONO (-5887 1362);
FORCEPROP 1 LASTPIN (-6075 1350) $PN 2
J 2
(-6037 1362);
DISPLAY 0.489362 (-6037 1362);
PAINT MONO (-6037 1362);
FORCEPROP 1 LAST VALUE 0
J 0
(-5875 1350);
DISPLAY 0.489362 (-5875 1350);
PAINT SKYBLUE (-5875 1350);
FORCEPROP 2 LAST CDS_LIB pure_quanta
J 2
(-5975 1350);
DISPLAY INVISIBLE (-5975 1350);
FORCEPROP 1 LAST PATH I112
J 2
(-5925 1500);
DISPLAY 0.978723 (-5925 1500);
PAINT WHITE (-5925 1500);
DISPLAY INVISIBLE (-5925 1500);
FORCEPROP 1 LAST WATTAGE 1/16W
J 0
(-6375 1275);
DISPLAY 0.489362 (-6375 1275);
PAINT SKYBLUE (-6375 1275);
DISPLAY INVISIBLE (-6375 1275);
FORCEPROP 1 LAST MATERIAL CHIP
J 2
(-6400 1275);
DISPLAY 0.489362 (-6400 1275);
PAINT SKYBLUE (-6400 1275);
DISPLAY INVISIBLE (-6400 1275);
FORCEPROP 1 LAST TOLERANCE 5%
J 2
(-5950 1275);
DISPLAY 0.489362 (-5950 1275);
PAINT SKYBLUE (-5950 1275);
DISPLAY INVISIBLE (-5950 1275);
FORCEPROP 1 LAST PART_NUMBER CS00002JB38
J 2
(-6000 1400);
DISPLAY 0.489362 (-6000 1400);
PAINT SKYBLUE (-6000 1400);
DISPLAY INVISIBLE (-6000 1400);
FORCEPROP 1 LAST PACK_TYPE 0402LF
J 2
(-6025 1275);
DISPLAY 0.489362 (-6025 1275);
PAINT SKYBLUE (-6025 1275);
DISPLAY INVISIBLE (-6025 1275);
FORCEADD OFFPAGE..1
(-7025 1400);
FORCEPROP 2 LAST $XR0 55 
J 0
(-7276 1400);
DISPLAY 0.638298 (-7276 1400);
PAINT MONO (-7276 1400);
FORCEPROP 2 LAST PATH I113
J 0
(-6975 1475);
DISPLAY 1.021277 (-6975 1475);
DISPLAY INVISIBLE (-6975 1475);
FORCEPROP 1 LAST COMMENT_BODY TRUE
J 0
(-6900 1300);
DISPLAY 0.872340 (-6900 1300);
PAINT GREEN (-6900 1300);
DISPLAY INVISIBLE (-6900 1300);
FORCEPROP 1 LAST OFFPAGE TRUE
J 0
(-6700 1275);
DISPLAY 0.872340 (-6700 1275);
PAINT GREEN (-6700 1275);
DISPLAY INVISIBLE (-6700 1275);
FORCEPROP 2 LAST CDS_LIB standard
J 0
(-7025 1400);
DISPLAY INVISIBLE (-7025 1400);
FORCEADD OFFPAGE..3
R 2
(-7025 1350);
FORCEPROP 2 LAST $XR0 55 
J 0
(-7304 1350);
DISPLAY 0.638298 (-7304 1350);
PAINT MONO (-7304 1350);
FORCEPROP 2 LAST PATH I114
J 0
(-6975 1425);
DISPLAY 1.021277 (-6975 1425);
DISPLAY INVISIBLE (-6975 1425);
FORCEPROP 1 LAST COMMENT_BODY TRUE
J 2
(-6975 1250);
DISPLAY 0.872340 (-6975 1250);
PAINT GREEN (-6975 1250);
DISPLAY INVISIBLE (-6975 1250);
FORCEPROP 1 LAST OFFPAGE TRUE
J 2
(-7350 1225);
DISPLAY 0.872340 (-7350 1225);
PAINT GREEN (-7350 1225);
DISPLAY INVISIBLE (-7350 1225);
FORCEPROP 2 LAST CDS_LIB standard
J 0
(-7025 1350);
DISPLAY INVISIBLE (-7025 1350);
FORCEADD Q_RES..1
(-6100 5325);
FORCEPROP 1 LAST LOCATION R2310
J 0
(-6275 5325);
DISPLAY 0.489362 (-6275 5325);
PAINT SKYBLUE (-6275 5325);
FORCEPROP 0 LAST $SEC 1
J 0
(-5975 5350);
DISPLAY 0.680851 (-5975 5350);
PAINT MONO (-5975 5350);
DISPLAY INVISIBLE (-5975 5350);
FORCEPROP 0 LAST CDS_SEC 1
J 0
(-5975 5350);
DISPLAY 1.021277 (-5975 5350);
DISPLAY INVISIBLE (-5975 5350);
FORCEPROP 1 LASTPIN (-6200 5325) $PN 1
J 0
(-6188 5337);
DISPLAY 0.489362 (-6188 5337);
PAINT MONO (-6188 5337);
FORCEPROP 1 LASTPIN (-6000 5325) $PN 2
J 0
(-6038 5337);
DISPLAY 0.489362 (-6038 5337);
PAINT MONO (-6038 5337);
FORCEPROP 1 LAST MATERIAL EMPTY
J 0
(-5975 5325);
DISPLAY 0.489362 (-5975 5325);
PAINT RED (-5975 5325);
FORCEPROP 1 LAST VALUE 0
J 2
(-6000 5325);
DISPLAY 0.489362 (-6000 5325);
PAINT SKYBLUE (-6000 5325);
FORCEPROP 2 LAST CDS_LIB pure_quanta
J 0
(-6100 5325);
DISPLAY INVISIBLE (-6100 5325);
FORCEPROP 1 LAST PATH I123
J 0
(-6150 5475);
DISPLAY 0.978723 (-6150 5475);
PAINT WHITE (-6150 5475);
DISPLAY INVISIBLE (-6150 5475);
FORCEPROP 1 LAST WATTAGE 1/16W
J 2
(-6125 5175);
DISPLAY 0.510638 (-6125 5175);
PAINT SKYBLUE (-6125 5175);
DISPLAY INVISIBLE (-6125 5175);
FORCEPROP 1 LAST TOLERANCE 5%
J 0
(-6100 5225);
DISPLAY 0.510638 (-6100 5225);
PAINT SKYBLUE (-6100 5225);
DISPLAY INVISIBLE (-6100 5225);
FORCEPROP 1 LAST PART_NUMBER CS00002JB38
J 0
(-6150 5425);
DISPLAY 0.510638 (-6150 5425);
PAINT SKYBLUE (-6150 5425);
DISPLAY INVISIBLE (-6150 5425);
FORCEPROP 1 LAST PACK_TYPE 0402LF
J 0
(-5850 5175);
DISPLAY 0.510638 (-5850 5175);
PAINT SKYBLUE (-5850 5175);
DISPLAY INVISIBLE (-5850 5175);
FORCEADD Q_RES..1
(-6100 5275);
FORCEPROP 1 LAST LOCATION R2311
J 0
(-6275 5275);
DISPLAY 0.489362 (-6275 5275);
PAINT SKYBLUE (-6275 5275);
FORCEPROP 0 LAST $SEC 1
J 0
(-5975 5300);
DISPLAY 0.680851 (-5975 5300);
PAINT MONO (-5975 5300);
DISPLAY INVISIBLE (-5975 5300);
FORCEPROP 0 LAST CDS_SEC 1
J 0
(-5975 5300);
DISPLAY 1.021277 (-5975 5300);
DISPLAY INVISIBLE (-5975 5300);
FORCEPROP 1 LASTPIN (-6200 5275) $PN 1
J 0
(-6188 5287);
DISPLAY 0.489362 (-6188 5287);
PAINT MONO (-6188 5287);
FORCEPROP 1 LASTPIN (-6000 5275) $PN 2
J 0
(-6038 5287);
DISPLAY 0.489362 (-6038 5287);
PAINT MONO (-6038 5287);
FORCEPROP 1 LAST MATERIAL EMPTY
J 0
(-5975 5275);
DISPLAY 0.489362 (-5975 5275);
PAINT RED (-5975 5275);
FORCEPROP 1 LAST VALUE 0
J 2
(-6000 5275);
DISPLAY 0.489362 (-6000 5275);
PAINT SKYBLUE (-6000 5275);
FORCEPROP 2 LAST CDS_LIB pure_quanta
J 0
(-6100 5275);
DISPLAY INVISIBLE (-6100 5275);
FORCEPROP 1 LAST PATH I124
J 0
(-6150 5425);
DISPLAY 0.978723 (-6150 5425);
PAINT WHITE (-6150 5425);
DISPLAY INVISIBLE (-6150 5425);
FORCEPROP 1 LAST WATTAGE 1/16W
J 2
(-6125 5125);
DISPLAY 0.510638 (-6125 5125);
PAINT SKYBLUE (-6125 5125);
DISPLAY INVISIBLE (-6125 5125);
FORCEPROP 1 LAST TOLERANCE 5%
J 0
(-6100 5175);
DISPLAY 0.510638 (-6100 5175);
PAINT SKYBLUE (-6100 5175);
DISPLAY INVISIBLE (-6100 5175);
FORCEPROP 1 LAST PART_NUMBER CS00002JB38
J 0
(-6150 5375);
DISPLAY 0.510638 (-6150 5375);
PAINT SKYBLUE (-6150 5375);
DISPLAY INVISIBLE (-6150 5375);
FORCEPROP 1 LAST PACK_TYPE 0402LF
J 0
(-5850 5125);
DISPLAY 0.510638 (-5850 5125);
PAINT SKYBLUE (-5850 5125);
DISPLAY INVISIBLE (-5850 5125);
FORCEADD Q_RES..1
(-3175 5325);
FORCEPROP 1 LAST LOCATION R1330
J 0
(-3275 5325);
DISPLAY 0.489362 (-3275 5325);
PAINT SKYBLUE (-3275 5325);
FORCEPROP 0 LAST $SEC 1
J 0
(-3275 5375);
DISPLAY 0.680851 (-3275 5375);
PAINT MONO (-3275 5375);
DISPLAY INVISIBLE (-3275 5375);
FORCEPROP 0 LAST CDS_SEC 1
J 0
(-3275 5375);
DISPLAY 0.680851 (-3275 5375);
DISPLAY INVISIBLE (-3275 5375);
FORCEPROP 1 LASTPIN (-3275 5325) $PN 1
J 0
(-3263 5337);
DISPLAY 0.489362 (-3263 5337);
PAINT MONO (-3263 5337);
FORCEPROP 1 LASTPIN (-3075 5325) $PN 2
J 0
(-3113 5337);
DISPLAY 0.489362 (-3113 5337);
PAINT MONO (-3113 5337);
FORCEPROP 1 LAST VALUE 0
J 2
(-3075 5325);
DISPLAY 0.489362 (-3075 5325);
PAINT SKYBLUE (-3075 5325);
FORCEPROP 1 LAST MATERIAL EMPTY
J 0
(-3050 5325);
DISPLAY 0.489362 (-3050 5325);
PAINT RED (-3050 5325);
FORCEPROP 2 LAST CDS_LIB pure_quanta
J 0
(-3175 5325);
DISPLAY INVISIBLE (-3175 5325);
FORCEPROP 1 LAST PATH I131
J 0
(-3225 5475);
DISPLAY 0.978723 (-3225 5475);
PAINT WHITE (-3225 5475);
DISPLAY INVISIBLE (-3225 5475);
FORCEPROP 1 LAST WATTAGE 1/16W
J 2
(-3200 5175);
DISPLAY 0.510638 (-3200 5175);
PAINT SKYBLUE (-3200 5175);
DISPLAY INVISIBLE (-3200 5175);
FORCEPROP 1 LAST TOLERANCE 5%
J 0
(-3175 5225);
DISPLAY 0.510638 (-3175 5225);
PAINT SKYBLUE (-3175 5225);
DISPLAY INVISIBLE (-3175 5225);
FORCEPROP 1 LAST PART_NUMBER CS00002JB38
J 0
(-3225 5425);
DISPLAY 0.510638 (-3225 5425);
PAINT SKYBLUE (-3225 5425);
DISPLAY INVISIBLE (-3225 5425);
FORCEPROP 1 LAST PACK_TYPE 0402LF
J 0
(-2925 5175);
DISPLAY 0.510638 (-2925 5175);
PAINT SKYBLUE (-2925 5175);
DISPLAY INVISIBLE (-2925 5175);
FORCEADD Q_RES..1
(-3175 5275);
FORCEPROP 1 LAST LOCATION R1331
J 0
(-3275 5275);
DISPLAY 0.489362 (-3275 5275);
PAINT SKYBLUE (-3275 5275);
FORCEPROP 0 LAST $SEC 1
J 0
(-3275 5325);
DISPLAY 0.680851 (-3275 5325);
PAINT MONO (-3275 5325);
DISPLAY INVISIBLE (-3275 5325);
FORCEPROP 0 LAST CDS_SEC 1
J 0
(-3275 5325);
DISPLAY 0.680851 (-3275 5325);
DISPLAY INVISIBLE (-3275 5325);
FORCEPROP 1 LASTPIN (-3275 5275) $PN 1
J 0
(-3263 5287);
DISPLAY 0.489362 (-3263 5287);
PAINT MONO (-3263 5287);
FORCEPROP 1 LASTPIN (-3075 5275) $PN 2
J 0
(-3113 5287);
DISPLAY 0.489362 (-3113 5287);
PAINT MONO (-3113 5287);
FORCEPROP 1 LAST MATERIAL EMPTY
J 0
(-3050 5275);
DISPLAY 0.489362 (-3050 5275);
PAINT RED (-3050 5275);
FORCEPROP 1 LAST VALUE 0
J 2
(-3075 5275);
DISPLAY 0.489362 (-3075 5275);
PAINT SKYBLUE (-3075 5275);
FORCEPROP 2 LAST CDS_LIB pure_quanta
J 0
(-3175 5275);
DISPLAY INVISIBLE (-3175 5275);
FORCEPROP 1 LAST PATH I132
J 0
(-3225 5425);
DISPLAY 0.978723 (-3225 5425);
PAINT WHITE (-3225 5425);
DISPLAY INVISIBLE (-3225 5425);
FORCEPROP 1 LAST WATTAGE 1/16W
J 2
(-3200 5125);
DISPLAY 0.510638 (-3200 5125);
PAINT SKYBLUE (-3200 5125);
DISPLAY INVISIBLE (-3200 5125);
FORCEPROP 1 LAST TOLERANCE 5%
J 0
(-3175 5175);
DISPLAY 0.510638 (-3175 5175);
PAINT SKYBLUE (-3175 5175);
DISPLAY INVISIBLE (-3175 5175);
FORCEPROP 1 LAST PART_NUMBER CS00002JB38
J 0
(-3225 5375);
DISPLAY 0.510638 (-3225 5375);
PAINT SKYBLUE (-3225 5375);
DISPLAY INVISIBLE (-3225 5375);
FORCEPROP 1 LAST PACK_TYPE 0402LF
J 0
(-2925 5125);
DISPLAY 0.510638 (-2925 5125);
PAINT SKYBLUE (-2925 5125);
DISPLAY INVISIBLE (-2925 5125);
FORCEADD Q_RES..1
(-3125 3875);
FORCEPROP 1 LAST LOCATION R1333
J 0
(-3225 3875);
DISPLAY 0.489362 (-3225 3875);
PAINT SKYBLUE (-3225 3875);
FORCEPROP 0 LAST $SEC 1
J 0
(-3225 3925);
DISPLAY 0.680851 (-3225 3925);
PAINT MONO (-3225 3925);
DISPLAY INVISIBLE (-3225 3925);
FORCEPROP 0 LAST CDS_SEC 1
J 0
(-3225 3925);
DISPLAY 0.680851 (-3225 3925);
DISPLAY INVISIBLE (-3225 3925);
FORCEPROP 1 LASTPIN (-3225 3875) $PN 1
J 0
(-3213 3887);
DISPLAY 0.489362 (-3213 3887);
PAINT MONO (-3213 3887);
FORCEPROP 1 LASTPIN (-3025 3875) $PN 2
J 0
(-3063 3887);
DISPLAY 0.489362 (-3063 3887);
PAINT MONO (-3063 3887);
FORCEPROP 1 LAST MATERIAL EMPTY
J 0
(-3000 3875);
DISPLAY 0.489362 (-3000 3875);
PAINT RED (-3000 3875);
FORCEPROP 1 LAST VALUE 0
J 2
(-3025 3875);
DISPLAY 0.489362 (-3025 3875);
PAINT SKYBLUE (-3025 3875);
FORCEPROP 2 LAST CDS_LIB pure_quanta
J 0
(-3125 3875);
DISPLAY INVISIBLE (-3125 3875);
FORCEPROP 1 LAST PATH I133
J 0
(-3175 4025);
DISPLAY 0.978723 (-3175 4025);
PAINT WHITE (-3175 4025);
DISPLAY INVISIBLE (-3175 4025);
FORCEPROP 1 LAST WATTAGE 1/16W
J 2
(-3150 3725);
DISPLAY 0.510638 (-3150 3725);
PAINT SKYBLUE (-3150 3725);
DISPLAY INVISIBLE (-3150 3725);
FORCEPROP 1 LAST TOLERANCE 5%
J 0
(-3125 3775);
DISPLAY 0.510638 (-3125 3775);
PAINT SKYBLUE (-3125 3775);
DISPLAY INVISIBLE (-3125 3775);
FORCEPROP 1 LAST PART_NUMBER CS00002JB38
J 0
(-3175 3975);
DISPLAY 0.510638 (-3175 3975);
PAINT SKYBLUE (-3175 3975);
DISPLAY INVISIBLE (-3175 3975);
FORCEPROP 1 LAST PACK_TYPE 0402LF
J 0
(-2875 3725);
DISPLAY 0.510638 (-2875 3725);
PAINT SKYBLUE (-2875 3725);
DISPLAY INVISIBLE (-2875 3725);
FORCEADD Q_RES..1
(-3125 3925);
FORCEPROP 1 LAST LOCATION R1332
J 0
(-3225 3925);
DISPLAY 0.489362 (-3225 3925);
PAINT SKYBLUE (-3225 3925);
FORCEPROP 0 LAST $SEC 1
J 0
(-3225 3975);
DISPLAY 0.680851 (-3225 3975);
PAINT MONO (-3225 3975);
DISPLAY INVISIBLE (-3225 3975);
FORCEPROP 0 LAST CDS_SEC 1
J 0
(-3225 3975);
DISPLAY 0.680851 (-3225 3975);
DISPLAY INVISIBLE (-3225 3975);
FORCEPROP 1 LASTPIN (-3225 3925) $PN 1
J 0
(-3213 3937);
DISPLAY 0.489362 (-3213 3937);
PAINT MONO (-3213 3937);
FORCEPROP 1 LASTPIN (-3025 3925) $PN 2
J 0
(-3063 3937);
DISPLAY 0.489362 (-3063 3937);
PAINT MONO (-3063 3937);
FORCEPROP 1 LAST VALUE 0
J 2
(-3025 3925);
DISPLAY 0.489362 (-3025 3925);
PAINT SKYBLUE (-3025 3925);
FORCEPROP 1 LAST MATERIAL EMPTY
J 0
(-3000 3925);
DISPLAY 0.489362 (-3000 3925);
PAINT RED (-3000 3925);
FORCEPROP 2 LAST CDS_LIB pure_quanta
J 0
(-3125 3925);
DISPLAY INVISIBLE (-3125 3925);
FORCEPROP 1 LAST PATH I134
J 0
(-3175 4075);
DISPLAY 0.978723 (-3175 4075);
PAINT WHITE (-3175 4075);
DISPLAY INVISIBLE (-3175 4075);
FORCEPROP 1 LAST WATTAGE 1/16W
J 2
(-3150 3775);
DISPLAY 0.510638 (-3150 3775);
PAINT SKYBLUE (-3150 3775);
DISPLAY INVISIBLE (-3150 3775);
FORCEPROP 1 LAST TOLERANCE 5%
J 0
(-3125 3825);
DISPLAY 0.510638 (-3125 3825);
PAINT SKYBLUE (-3125 3825);
DISPLAY INVISIBLE (-3125 3825);
FORCEPROP 1 LAST PART_NUMBER CS00002JB38
J 0
(-3175 4025);
DISPLAY 0.510638 (-3175 4025);
PAINT SKYBLUE (-3175 4025);
DISPLAY INVISIBLE (-3175 4025);
FORCEPROP 1 LAST PACK_TYPE 0402LF
J 0
(-2875 3775);
DISPLAY 0.510638 (-2875 3775);
PAINT SKYBLUE (-2875 3775);
DISPLAY INVISIBLE (-2875 3775);
FORCEADD Q_RES..1
(-6050 3925);
FORCEPROP 1 LAST LOCATION R986
J 0
(-6225 3925);
DISPLAY 0.489362 (-6225 3925);
PAINT SKYBLUE (-6225 3925);
FORCEPROP 0 LAST $SEC 1
J 0
(-5925 3950);
DISPLAY 0.680851 (-5925 3950);
PAINT MONO (-5925 3950);
DISPLAY INVISIBLE (-5925 3950);
FORCEPROP 0 LAST CDS_SEC 1
J 0
(-5925 3950);
DISPLAY 1.021277 (-5925 3950);
DISPLAY INVISIBLE (-5925 3950);
FORCEPROP 1 LASTPIN (-6150 3925) $PN 1
J 0
(-6138 3937);
DISPLAY 0.489362 (-6138 3937);
PAINT MONO (-6138 3937);
FORCEPROP 1 LASTPIN (-5950 3925) $PN 2
J 0
(-5988 3937);
DISPLAY 0.489362 (-5988 3937);
PAINT MONO (-5988 3937);
FORCEPROP 1 LAST MATERIAL EMPTY
J 0
(-5925 3925);
DISPLAY 0.489362 (-5925 3925);
PAINT RED (-5925 3925);
FORCEPROP 1 LAST VALUE 0
J 2
(-5950 3925);
DISPLAY 0.489362 (-5950 3925);
PAINT SKYBLUE (-5950 3925);
FORCEPROP 2 LAST CDS_LIB pure_quanta
J 0
(-6050 3925);
DISPLAY INVISIBLE (-6050 3925);
FORCEPROP 1 LAST PATH I135
J 0
(-6100 4075);
DISPLAY 0.978723 (-6100 4075);
PAINT WHITE (-6100 4075);
DISPLAY INVISIBLE (-6100 4075);
FORCEPROP 1 LAST WATTAGE 1/16W
J 2
(-6075 3775);
DISPLAY 0.510638 (-6075 3775);
PAINT SKYBLUE (-6075 3775);
DISPLAY INVISIBLE (-6075 3775);
FORCEPROP 1 LAST TOLERANCE 5%
J 0
(-6050 3825);
DISPLAY 0.510638 (-6050 3825);
PAINT SKYBLUE (-6050 3825);
DISPLAY INVISIBLE (-6050 3825);
FORCEPROP 1 LAST PART_NUMBER CS00002JB38
J 0
(-6100 4025);
DISPLAY 0.510638 (-6100 4025);
PAINT SKYBLUE (-6100 4025);
DISPLAY INVISIBLE (-6100 4025);
FORCEPROP 1 LAST PACK_TYPE 0402LF
J 0
(-5800 3775);
DISPLAY 0.510638 (-5800 3775);
PAINT SKYBLUE (-5800 3775);
DISPLAY INVISIBLE (-5800 3775);
FORCEADD Q_RES..1
(-6050 3875);
FORCEPROP 1 LAST LOCATION R987
J 0
(-6225 3875);
DISPLAY 0.489362 (-6225 3875);
PAINT SKYBLUE (-6225 3875);
FORCEPROP 0 LAST $SEC 1
J 0
(-5925 3900);
DISPLAY 0.680851 (-5925 3900);
PAINT MONO (-5925 3900);
DISPLAY INVISIBLE (-5925 3900);
FORCEPROP 0 LAST CDS_SEC 1
J 0
(-5925 3900);
DISPLAY 1.021277 (-5925 3900);
DISPLAY INVISIBLE (-5925 3900);
FORCEPROP 1 LASTPIN (-6150 3875) $PN 1
J 0
(-6138 3887);
DISPLAY 0.489362 (-6138 3887);
PAINT MONO (-6138 3887);
FORCEPROP 1 LASTPIN (-5950 3875) $PN 2
J 0
(-5988 3887);
DISPLAY 0.489362 (-5988 3887);
PAINT MONO (-5988 3887);
FORCEPROP 1 LAST MATERIAL EMPTY
J 0
(-5925 3875);
DISPLAY 0.489362 (-5925 3875);
PAINT RED (-5925 3875);
FORCEPROP 1 LAST VALUE 0
J 2
(-5950 3875);
DISPLAY 0.489362 (-5950 3875);
PAINT SKYBLUE (-5950 3875);
FORCEPROP 2 LAST CDS_LIB pure_quanta
J 0
(-6050 3875);
DISPLAY INVISIBLE (-6050 3875);
FORCEPROP 1 LAST PATH I136
J 0
(-6100 4025);
DISPLAY 0.978723 (-6100 4025);
PAINT WHITE (-6100 4025);
DISPLAY INVISIBLE (-6100 4025);
FORCEPROP 1 LAST WATTAGE 1/16W
J 2
(-6075 3725);
DISPLAY 0.510638 (-6075 3725);
PAINT SKYBLUE (-6075 3725);
DISPLAY INVISIBLE (-6075 3725);
FORCEPROP 1 LAST TOLERANCE 5%
J 0
(-6050 3775);
DISPLAY 0.510638 (-6050 3775);
PAINT SKYBLUE (-6050 3775);
DISPLAY INVISIBLE (-6050 3775);
FORCEPROP 1 LAST PART_NUMBER CS00002JB38
J 0
(-6100 3975);
DISPLAY 0.510638 (-6100 3975);
PAINT SKYBLUE (-6100 3975);
DISPLAY INVISIBLE (-6100 3975);
FORCEPROP 1 LAST PACK_TYPE 0402LF
J 0
(-5800 3725);
DISPLAY 0.510638 (-5800 3725);
PAINT SKYBLUE (-5800 3725);
DISPLAY INVISIBLE (-5800 3725);
FORCEADD Q_RES..1
(-6000 2350);
FORCEPROP 1 LAST LOCATION R989
J 0
(-6175 2350);
DISPLAY 0.489362 (-6175 2350);
PAINT SKYBLUE (-6175 2350);
FORCEPROP 0 LAST $SEC 1
J 0
(-5875 2375);
DISPLAY 0.680851 (-5875 2375);
PAINT MONO (-5875 2375);
DISPLAY INVISIBLE (-5875 2375);
FORCEPROP 0 LAST CDS_SEC 1
J 0
(-5875 2375);
DISPLAY 1.021277 (-5875 2375);
DISPLAY INVISIBLE (-5875 2375);
FORCEPROP 1 LASTPIN (-6100 2350) $PN 1
J 0
(-6088 2362);
DISPLAY 0.489362 (-6088 2362);
PAINT MONO (-6088 2362);
FORCEPROP 1 LASTPIN (-5900 2350) $PN 2
J 0
(-5938 2362);
DISPLAY 0.489362 (-5938 2362);
PAINT MONO (-5938 2362);
FORCEPROP 1 LAST VALUE 0
J 2
(-5900 2350);
DISPLAY 0.489362 (-5900 2350);
PAINT SKYBLUE (-5900 2350);
FORCEPROP 1 LAST MATERIAL EMPTY
J 0
(-5875 2350);
DISPLAY 0.489362 (-5875 2350);
PAINT RED (-5875 2350);
FORCEPROP 2 LAST CDS_LIB pure_quanta
J 0
(-6000 2350);
DISPLAY INVISIBLE (-6000 2350);
FORCEPROP 1 LAST PATH I137
J 0
(-6050 2500);
DISPLAY 0.978723 (-6050 2500);
PAINT WHITE (-6050 2500);
DISPLAY INVISIBLE (-6050 2500);
FORCEPROP 1 LAST WATTAGE 1/16W
J 2
(-6025 2200);
DISPLAY 0.510638 (-6025 2200);
PAINT SKYBLUE (-6025 2200);
DISPLAY INVISIBLE (-6025 2200);
FORCEPROP 1 LAST TOLERANCE 5%
J 0
(-6000 2250);
DISPLAY 0.510638 (-6000 2250);
PAINT SKYBLUE (-6000 2250);
DISPLAY INVISIBLE (-6000 2250);
FORCEPROP 1 LAST PART_NUMBER CS00002JB38
J 0
(-6050 2450);
DISPLAY 0.510638 (-6050 2450);
PAINT SKYBLUE (-6050 2450);
DISPLAY INVISIBLE (-6050 2450);
FORCEPROP 1 LAST PACK_TYPE 0402LF
J 0
(-5750 2200);
DISPLAY 0.510638 (-5750 2200);
PAINT SKYBLUE (-5750 2200);
DISPLAY INVISIBLE (-5750 2200);
FORCEADD Q_RES..1
(-6000 2400);
FORCEPROP 1 LAST LOCATION R988
J 0
(-6175 2400);
DISPLAY 0.489362 (-6175 2400);
PAINT SKYBLUE (-6175 2400);
FORCEPROP 0 LAST $SEC 1
J 0
(-5875 2425);
DISPLAY 0.680851 (-5875 2425);
PAINT MONO (-5875 2425);
DISPLAY INVISIBLE (-5875 2425);
FORCEPROP 0 LAST CDS_SEC 1
J 0
(-5875 2425);
DISPLAY 1.021277 (-5875 2425);
DISPLAY INVISIBLE (-5875 2425);
FORCEPROP 1 LASTPIN (-6100 2400) $PN 1
J 0
(-6088 2412);
DISPLAY 0.489362 (-6088 2412);
PAINT MONO (-6088 2412);
FORCEPROP 1 LASTPIN (-5900 2400) $PN 2
J 0
(-5938 2412);
DISPLAY 0.489362 (-5938 2412);
PAINT MONO (-5938 2412);
FORCEPROP 1 LAST VALUE 0
J 2
(-5900 2400);
DISPLAY 0.489362 (-5900 2400);
PAINT SKYBLUE (-5900 2400);
FORCEPROP 1 LAST MATERIAL EMPTY
J 0
(-5875 2400);
DISPLAY 0.489362 (-5875 2400);
PAINT RED (-5875 2400);
FORCEPROP 2 LAST CDS_LIB pure_quanta
J 0
(-6000 2400);
DISPLAY INVISIBLE (-6000 2400);
FORCEPROP 1 LAST PATH I138
J 0
(-6050 2550);
DISPLAY 0.978723 (-6050 2550);
PAINT WHITE (-6050 2550);
DISPLAY INVISIBLE (-6050 2550);
FORCEPROP 1 LAST WATTAGE 1/16W
J 2
(-6025 2250);
DISPLAY 0.510638 (-6025 2250);
PAINT SKYBLUE (-6025 2250);
DISPLAY INVISIBLE (-6025 2250);
FORCEPROP 1 LAST TOLERANCE 5%
J 0
(-6000 2300);
DISPLAY 0.510638 (-6000 2300);
PAINT SKYBLUE (-6000 2300);
DISPLAY INVISIBLE (-6000 2300);
FORCEPROP 1 LAST PART_NUMBER CS00002JB38
J 0
(-6050 2500);
DISPLAY 0.510638 (-6050 2500);
PAINT SKYBLUE (-6050 2500);
DISPLAY INVISIBLE (-6050 2500);
FORCEPROP 1 LAST PACK_TYPE 0402LF
J 0
(-5750 2250);
DISPLAY 0.510638 (-5750 2250);
PAINT SKYBLUE (-5750 2250);
DISPLAY INVISIBLE (-5750 2250);
FORCEADD Q_RES..1
(-3075 2400);
FORCEPROP 1 LAST LOCATION R1334
J 0
(-3175 2400);
DISPLAY 0.489362 (-3175 2400);
PAINT SKYBLUE (-3175 2400);
FORCEPROP 0 LAST $SEC 1
J 0
(-3175 2450);
DISPLAY 0.680851 (-3175 2450);
PAINT MONO (-3175 2450);
DISPLAY INVISIBLE (-3175 2450);
FORCEPROP 0 LAST CDS_SEC 1
J 0
(-3175 2450);
DISPLAY 0.680851 (-3175 2450);
DISPLAY INVISIBLE (-3175 2450);
FORCEPROP 1 LASTPIN (-3175 2400) $PN 1
J 0
(-3163 2412);
DISPLAY 0.489362 (-3163 2412);
PAINT MONO (-3163 2412);
FORCEPROP 1 LASTPIN (-2975 2400) $PN 2
J 0
(-3013 2412);
DISPLAY 0.489362 (-3013 2412);
PAINT MONO (-3013 2412);
FORCEPROP 1 LAST MATERIAL EMPTY
J 0
(-2950 2400);
DISPLAY 0.489362 (-2950 2400);
PAINT RED (-2950 2400);
FORCEPROP 1 LAST VALUE 0
J 2
(-2975 2400);
DISPLAY 0.489362 (-2975 2400);
PAINT SKYBLUE (-2975 2400);
FORCEPROP 2 LAST CDS_LIB pure_quanta
J 0
(-3075 2400);
DISPLAY INVISIBLE (-3075 2400);
FORCEPROP 1 LAST PATH I139
J 0
(-3125 2550);
DISPLAY 0.978723 (-3125 2550);
PAINT WHITE (-3125 2550);
DISPLAY INVISIBLE (-3125 2550);
FORCEPROP 1 LAST WATTAGE 1/16W
J 2
(-3100 2250);
DISPLAY 0.510638 (-3100 2250);
PAINT SKYBLUE (-3100 2250);
DISPLAY INVISIBLE (-3100 2250);
FORCEPROP 1 LAST TOLERANCE 5%
J 0
(-3075 2300);
DISPLAY 0.510638 (-3075 2300);
PAINT SKYBLUE (-3075 2300);
DISPLAY INVISIBLE (-3075 2300);
FORCEPROP 1 LAST PART_NUMBER CS00002JB38
J 0
(-3125 2500);
DISPLAY 0.510638 (-3125 2500);
PAINT SKYBLUE (-3125 2500);
DISPLAY INVISIBLE (-3125 2500);
FORCEPROP 1 LAST PACK_TYPE 0402LF
J 0
(-2825 2250);
DISPLAY 0.510638 (-2825 2250);
PAINT SKYBLUE (-2825 2250);
DISPLAY INVISIBLE (-2825 2250);
FORCEADD OFFPAGE..3
R 2
(-6025 5625);
FORCEPROP 2 LAST $XR0 117 
J 0
(-6335 5625);
DISPLAY 0.638298 (-6335 5625);
PAINT MONO (-6335 5625);
FORCEPROP 2 LAST PATH I14
J 0
(-5975 5700);
DISPLAY 1.021277 (-5975 5700);
DISPLAY INVISIBLE (-5975 5700);
FORCEPROP 1 LAST COMMENT_BODY TRUE
J 2
(-5975 5525);
DISPLAY 0.872340 (-5975 5525);
PAINT GREEN (-5975 5525);
DISPLAY INVISIBLE (-5975 5525);
FORCEPROP 1 LAST OFFPAGE TRUE
J 2
(-6350 5500);
DISPLAY 0.872340 (-6350 5500);
PAINT GREEN (-6350 5500);
DISPLAY INVISIBLE (-6350 5500);
FORCEPROP 2 LAST CDS_LIB standard
J 2
(-6025 5625);
DISPLAY INVISIBLE (-6025 5625);
FORCEADD Q_RES..1
(-3075 2350);
FORCEPROP 1 LAST LOCATION R1335
J 0
(-3175 2350);
DISPLAY 0.489362 (-3175 2350);
PAINT SKYBLUE (-3175 2350);
FORCEPROP 0 LAST $SEC 1
J 0
(-3175 2400);
DISPLAY 0.680851 (-3175 2400);
PAINT MONO (-3175 2400);
DISPLAY INVISIBLE (-3175 2400);
FORCEPROP 0 LAST CDS_SEC 1
J 0
(-3175 2400);
DISPLAY 0.680851 (-3175 2400);
DISPLAY INVISIBLE (-3175 2400);
FORCEPROP 1 LASTPIN (-3175 2350) $PN 1
J 0
(-3163 2362);
DISPLAY 0.489362 (-3163 2362);
PAINT MONO (-3163 2362);
FORCEPROP 1 LASTPIN (-2975 2350) $PN 2
J 0
(-3013 2362);
DISPLAY 0.489362 (-3013 2362);
PAINT MONO (-3013 2362);
FORCEPROP 1 LAST MATERIAL EMPTY
J 0
(-2950 2350);
DISPLAY 0.489362 (-2950 2350);
PAINT RED (-2950 2350);
FORCEPROP 1 LAST VALUE 0
J 2
(-2975 2350);
DISPLAY 0.489362 (-2975 2350);
PAINT SKYBLUE (-2975 2350);
FORCEPROP 2 LAST CDS_LIB pure_quanta
J 0
(-3075 2350);
DISPLAY INVISIBLE (-3075 2350);
FORCEPROP 1 LAST PATH I140
J 0
(-3125 2500);
DISPLAY 0.978723 (-3125 2500);
PAINT WHITE (-3125 2500);
DISPLAY INVISIBLE (-3125 2500);
FORCEPROP 1 LAST WATTAGE 1/16W
J 2
(-3100 2200);
DISPLAY 0.510638 (-3100 2200);
PAINT SKYBLUE (-3100 2200);
DISPLAY INVISIBLE (-3100 2200);
FORCEPROP 1 LAST TOLERANCE 5%
J 0
(-3075 2250);
DISPLAY 0.510638 (-3075 2250);
PAINT SKYBLUE (-3075 2250);
DISPLAY INVISIBLE (-3075 2250);
FORCEPROP 1 LAST PART_NUMBER CS00002JB38
J 0
(-3125 2450);
DISPLAY 0.510638 (-3125 2450);
PAINT SKYBLUE (-3125 2450);
DISPLAY INVISIBLE (-3125 2450);
FORCEPROP 1 LAST PACK_TYPE 0402LF
J 0
(-2825 2200);
DISPLAY 0.510638 (-2825 2200);
PAINT SKYBLUE (-2825 2200);
DISPLAY INVISIBLE (-2825 2200);
FORCEADD Q_RES..1
(-5950 900);
FORCEPROP 1 LAST LOCATION R991
J 0
(-6125 900);
DISPLAY 0.489362 (-6125 900);
PAINT SKYBLUE (-6125 900);
FORCEPROP 0 LAST $SEC 1
J 0
(-5825 925);
DISPLAY 0.680851 (-5825 925);
PAINT MONO (-5825 925);
DISPLAY INVISIBLE (-5825 925);
FORCEPROP 0 LAST CDS_SEC 1
J 0
(-5825 925);
DISPLAY 1.021277 (-5825 925);
DISPLAY INVISIBLE (-5825 925);
FORCEPROP 1 LASTPIN (-6050 900) $PN 1
J 0
(-6038 912);
DISPLAY 0.489362 (-6038 912);
PAINT MONO (-6038 912);
FORCEPROP 1 LASTPIN (-5850 900) $PN 2
J 0
(-5888 912);
DISPLAY 0.489362 (-5888 912);
PAINT MONO (-5888 912);
FORCEPROP 1 LAST MATERIAL EMPTY
J 0
(-5825 900);
DISPLAY 0.489362 (-5825 900);
PAINT RED (-5825 900);
FORCEPROP 1 LAST VALUE 0
J 2
(-5850 900);
DISPLAY 0.489362 (-5850 900);
PAINT SKYBLUE (-5850 900);
FORCEPROP 2 LAST CDS_LIB pure_quanta
J 0
(-5950 900);
DISPLAY INVISIBLE (-5950 900);
FORCEPROP 1 LAST PATH I141
J 0
(-6000 1050);
DISPLAY 0.978723 (-6000 1050);
PAINT WHITE (-6000 1050);
DISPLAY INVISIBLE (-6000 1050);
FORCEPROP 1 LAST WATTAGE 1/16W
J 2
(-5975 750);
DISPLAY 0.510638 (-5975 750);
PAINT SKYBLUE (-5975 750);
DISPLAY INVISIBLE (-5975 750);
FORCEPROP 1 LAST TOLERANCE 5%
J 0
(-5950 800);
DISPLAY 0.510638 (-5950 800);
PAINT SKYBLUE (-5950 800);
DISPLAY INVISIBLE (-5950 800);
FORCEPROP 1 LAST PART_NUMBER CS00002JB38
J 0
(-6000 1000);
DISPLAY 0.510638 (-6000 1000);
PAINT SKYBLUE (-6000 1000);
DISPLAY INVISIBLE (-6000 1000);
FORCEPROP 1 LAST PACK_TYPE 0402LF
J 0
(-5700 750);
DISPLAY 0.510638 (-5700 750);
PAINT SKYBLUE (-5700 750);
DISPLAY INVISIBLE (-5700 750);
FORCEADD Q_RES..1
(-5950 950);
FORCEPROP 1 LAST LOCATION R990
J 0
(-6125 950);
DISPLAY 0.489362 (-6125 950);
PAINT SKYBLUE (-6125 950);
FORCEPROP 0 LAST $SEC 1
J 0
(-5825 975);
DISPLAY 0.680851 (-5825 975);
PAINT MONO (-5825 975);
DISPLAY INVISIBLE (-5825 975);
FORCEPROP 0 LAST CDS_SEC 1
J 0
(-5825 975);
DISPLAY 1.021277 (-5825 975);
DISPLAY INVISIBLE (-5825 975);
FORCEPROP 1 LASTPIN (-6050 950) $PN 1
J 0
(-6038 962);
DISPLAY 0.489362 (-6038 962);
PAINT MONO (-6038 962);
FORCEPROP 1 LASTPIN (-5850 950) $PN 2
J 0
(-5888 962);
DISPLAY 0.489362 (-5888 962);
PAINT MONO (-5888 962);
FORCEPROP 1 LAST MATERIAL EMPTY
J 0
(-5825 950);
DISPLAY 0.489362 (-5825 950);
PAINT RED (-5825 950);
FORCEPROP 1 LAST VALUE 0
J 2
(-5850 950);
DISPLAY 0.489362 (-5850 950);
PAINT SKYBLUE (-5850 950);
FORCEPROP 2 LAST CDS_LIB pure_quanta
J 0
(-5950 950);
DISPLAY INVISIBLE (-5950 950);
FORCEPROP 1 LAST PATH I142
J 0
(-6000 1100);
DISPLAY 0.978723 (-6000 1100);
PAINT WHITE (-6000 1100);
DISPLAY INVISIBLE (-6000 1100);
FORCEPROP 1 LAST WATTAGE 1/16W
J 2
(-5975 800);
DISPLAY 0.510638 (-5975 800);
PAINT SKYBLUE (-5975 800);
DISPLAY INVISIBLE (-5975 800);
FORCEPROP 1 LAST TOLERANCE 5%
J 0
(-5950 850);
DISPLAY 0.510638 (-5950 850);
PAINT SKYBLUE (-5950 850);
DISPLAY INVISIBLE (-5950 850);
FORCEPROP 1 LAST PART_NUMBER CS00002JB38
J 0
(-6000 1050);
DISPLAY 0.510638 (-6000 1050);
PAINT SKYBLUE (-6000 1050);
DISPLAY INVISIBLE (-6000 1050);
FORCEPROP 1 LAST PACK_TYPE 0402LF
J 0
(-5700 800);
DISPLAY 0.510638 (-5700 800);
PAINT SKYBLUE (-5700 800);
DISPLAY INVISIBLE (-5700 800);
FORCEADD Q_RES..1
(-3025 950);
FORCEPROP 1 LAST LOCATION R1336
J 0
(-3125 950);
DISPLAY 0.489362 (-3125 950);
PAINT SKYBLUE (-3125 950);
FORCEPROP 0 LAST $SEC 1
J 0
(-3125 1000);
DISPLAY 0.680851 (-3125 1000);
PAINT MONO (-3125 1000);
DISPLAY INVISIBLE (-3125 1000);
FORCEPROP 0 LAST CDS_SEC 1
J 0
(-3125 1000);
DISPLAY 0.680851 (-3125 1000);
DISPLAY INVISIBLE (-3125 1000);
FORCEPROP 1 LASTPIN (-3125 950) $PN 1
J 0
(-3113 962);
DISPLAY 0.489362 (-3113 962);
PAINT MONO (-3113 962);
FORCEPROP 1 LASTPIN (-2925 950) $PN 2
J 0
(-2963 962);
DISPLAY 0.489362 (-2963 962);
PAINT MONO (-2963 962);
FORCEPROP 1 LAST MATERIAL EMPTY
J 0
(-2900 950);
DISPLAY 0.489362 (-2900 950);
PAINT RED (-2900 950);
FORCEPROP 1 LAST VALUE 0
J 2
(-2925 950);
DISPLAY 0.489362 (-2925 950);
PAINT SKYBLUE (-2925 950);
FORCEPROP 2 LAST CDS_LIB pure_quanta
J 0
(-3025 950);
DISPLAY INVISIBLE (-3025 950);
FORCEPROP 1 LAST PATH I143
J 0
(-3075 1100);
DISPLAY 0.978723 (-3075 1100);
PAINT WHITE (-3075 1100);
DISPLAY INVISIBLE (-3075 1100);
FORCEPROP 1 LAST WATTAGE 1/16W
J 2
(-3050 800);
DISPLAY 0.510638 (-3050 800);
PAINT SKYBLUE (-3050 800);
DISPLAY INVISIBLE (-3050 800);
FORCEPROP 1 LAST TOLERANCE 5%
J 0
(-3025 850);
DISPLAY 0.510638 (-3025 850);
PAINT SKYBLUE (-3025 850);
DISPLAY INVISIBLE (-3025 850);
FORCEPROP 1 LAST PART_NUMBER CS00002JB38
J 0
(-3075 1050);
DISPLAY 0.510638 (-3075 1050);
PAINT SKYBLUE (-3075 1050);
DISPLAY INVISIBLE (-3075 1050);
FORCEPROP 1 LAST PACK_TYPE 0402LF
J 0
(-2775 800);
DISPLAY 0.510638 (-2775 800);
PAINT SKYBLUE (-2775 800);
DISPLAY INVISIBLE (-2775 800);
FORCEADD Q_RES..1
(-3025 900);
FORCEPROP 1 LAST LOCATION R1337
J 0
(-3125 900);
DISPLAY 0.489362 (-3125 900);
PAINT SKYBLUE (-3125 900);
FORCEPROP 0 LAST $SEC 1
J 0
(-3125 950);
DISPLAY 0.680851 (-3125 950);
PAINT MONO (-3125 950);
DISPLAY INVISIBLE (-3125 950);
FORCEPROP 0 LAST CDS_SEC 1
J 0
(-3125 950);
DISPLAY 0.680851 (-3125 950);
DISPLAY INVISIBLE (-3125 950);
FORCEPROP 1 LASTPIN (-3125 900) $PN 1
J 0
(-3113 912);
DISPLAY 0.489362 (-3113 912);
PAINT MONO (-3113 912);
FORCEPROP 1 LASTPIN (-2925 900) $PN 2
J 0
(-2963 912);
DISPLAY 0.489362 (-2963 912);
PAINT MONO (-2963 912);
FORCEPROP 1 LAST MATERIAL EMPTY
J 0
(-2900 900);
DISPLAY 0.489362 (-2900 900);
PAINT RED (-2900 900);
FORCEPROP 1 LAST VALUE 0
J 2
(-2925 900);
DISPLAY 0.489362 (-2925 900);
PAINT SKYBLUE (-2925 900);
FORCEPROP 2 LAST CDS_LIB pure_quanta
J 0
(-3025 900);
DISPLAY INVISIBLE (-3025 900);
FORCEPROP 1 LAST PATH I144
J 0
(-3075 1050);
DISPLAY 0.978723 (-3075 1050);
PAINT WHITE (-3075 1050);
DISPLAY INVISIBLE (-3075 1050);
FORCEPROP 1 LAST WATTAGE 1/16W
J 2
(-3050 750);
DISPLAY 0.510638 (-3050 750);
PAINT SKYBLUE (-3050 750);
DISPLAY INVISIBLE (-3050 750);
FORCEPROP 1 LAST TOLERANCE 5%
J 0
(-3025 800);
DISPLAY 0.510638 (-3025 800);
PAINT SKYBLUE (-3025 800);
DISPLAY INVISIBLE (-3025 800);
FORCEPROP 1 LAST PART_NUMBER CS00002JB38
J 0
(-3075 1000);
DISPLAY 0.510638 (-3075 1000);
PAINT SKYBLUE (-3075 1000);
DISPLAY INVISIBLE (-3075 1000);
FORCEPROP 1 LAST PACK_TYPE 0402LF
J 0
(-2775 750);
DISPLAY 0.510638 (-2775 750);
PAINT SKYBLUE (-2775 750);
DISPLAY INVISIBLE (-2775 750);
FORCEADD Q_RES..2
(-3450 6100);
FORCEPROP 1 LAST LOCATION R5006
J 0
(-3405 6225);
DISPLAY 0.489362 (-3405 6225);
PAINT SKYBLUE (-3405 6225);
FORCEPROP 0 LAST $SEC 1
J 0
(-3400 6250);
DISPLAY 0.680851 (-3400 6250);
PAINT MONO (-3400 6250);
DISPLAY INVISIBLE (-3400 6250);
FORCEPROP 0 LAST CDS_SEC 1
J 0
(-3400 6250);
DISPLAY 0.680851 (-3400 6250);
DISPLAY INVISIBLE (-3400 6250);
FORCEPROP 1 LASTPIN (-3450 6200) $PN 1
J 0
(-3445 6162);
DISPLAY 0.787234 (-3445 6162);
PAINT MONO (-3445 6162);
FORCEPROP 1 LASTPIN (-3450 6000) $PN 2
J 0
(-3445 6010);
DISPLAY 0.787234 (-3445 6010);
PAINT MONO (-3445 6010);
FORCEPROP 1 LAST TOLERANCE 1%
J 0
(-3405 6125);
DISPLAY 0.489362 (-3405 6125);
PAINT SKYBLUE (-3405 6125);
FORCEPROP 1 LAST VALUE 1K
J 0
(-3405 6175);
DISPLAY 0.489362 (-3405 6175);
PAINT SKYBLUE (-3405 6175);
FORCEPROP 1 LAST PACK_TYPE 0402LF
J 0
(-3400 5975);
DISPLAY 0.489362 (-3400 5975);
PAINT SKYBLUE (-3400 5975);
FORCEPROP 1 LAST WATTAGE 1/16W
J 0
(-3410 6075);
DISPLAY 0.489362 (-3410 6075);
PAINT SKYBLUE (-3410 6075);
FORCEPROP 1 LAST MATERIAL CHIP
J 0
(-3410 6025);
DISPLAY 0.489362 (-3410 6025);
PAINT SKYBLUE (-3410 6025);
FORCEPROP 2 LAST CDS_LIB pure_quanta
J 0
(-3450 6100);
DISPLAY INVISIBLE (-3450 6100);
FORCEPROP 1 LAST PATH I145
J 0
(-3400 6275);
DISPLAY 0.978723 (-3400 6275);
PAINT WHITE (-3400 6275);
DISPLAY INVISIBLE (-3400 6275);
FORCEPROP 1 LAST PART_NUMBER TMP_QCS21002FB24
J 0
(-3410 5975);
DISPLAY 0.489362 (-3410 5975);
PAINT SKYBLUE (-3410 5975);
DISPLAY INVISIBLE (-3410 5975);
FORCEADD VCC_CORE..1
(-3450 6375);
FORCEPROP 3 LASTPIN (-3450 6325) SIG_NAME PVDD11_S3_P0\g
J 0
(-3440 6335);
DISPLAY 0.659574 (-3440 6335);
PAINT MONO (-3440 6335);
DISPLAY INVISIBLE (-3440 6335);
FORCEPROP 1 LAST HDL_POWER PVDD11_S3_P0
J 1
(-3450 6425);
DISPLAY 0.489362 (-3450 6425);
PAINT GREEN (-3450 6425);
FORCEPROP 2 LAST CDS_LIB pure_quanta_power
J 0
(-3450 6375);
DISPLAY INVISIBLE (-3450 6375);
FORCEPROP 1 LAST PATH I146
J 0
(-3400 6400);
DISPLAY 0.872340 (-3400 6400);
PAINT AQUA (-3400 6400);
DISPLAY INVISIBLE (-3400 6400);
FORCEADD Q_RES..2
(-3650 6100);
FORCEPROP 1 LAST LOCATION R5007
J 0
(-3605 6225);
DISPLAY 0.489362 (-3605 6225);
PAINT SKYBLUE (-3605 6225);
FORCEPROP 0 LAST $SEC 1
J 0
(-3600 6250);
DISPLAY 0.680851 (-3600 6250);
PAINT MONO (-3600 6250);
DISPLAY INVISIBLE (-3600 6250);
FORCEPROP 0 LAST CDS_SEC 1
J 0
(-3600 6250);
DISPLAY 0.680851 (-3600 6250);
DISPLAY INVISIBLE (-3600 6250);
FORCEPROP 1 LASTPIN (-3650 6200) $PN 1
J 0
(-3645 6162);
DISPLAY 0.787234 (-3645 6162);
PAINT MONO (-3645 6162);
FORCEPROP 1 LASTPIN (-3650 6000) $PN 2
J 0
(-3645 6010);
DISPLAY 0.787234 (-3645 6010);
PAINT MONO (-3645 6010);
FORCEPROP 1 LAST VALUE 1K
J 0
(-3605 6175);
DISPLAY 0.489362 (-3605 6175);
PAINT SKYBLUE (-3605 6175);
FORCEPROP 1 LAST TOLERANCE 1%
J 0
(-3605 6125);
DISPLAY 0.489362 (-3605 6125);
PAINT SKYBLUE (-3605 6125);
FORCEPROP 1 LAST PACK_TYPE 0402LF
J 0
(-3600 5975);
DISPLAY 0.489362 (-3600 5975);
PAINT SKYBLUE (-3600 5975);
FORCEPROP 1 LAST WATTAGE 1/16W
J 0
(-3610 6075);
DISPLAY 0.489362 (-3610 6075);
PAINT SKYBLUE (-3610 6075);
FORCEPROP 1 LAST MATERIAL CHIP
J 0
(-3610 6025);
DISPLAY 0.489362 (-3610 6025);
PAINT SKYBLUE (-3610 6025);
FORCEPROP 2 LAST CDS_LIB pure_quanta
J 0
(-3650 6100);
DISPLAY INVISIBLE (-3650 6100);
FORCEPROP 1 LAST PATH I147
J 0
(-3600 6275);
DISPLAY 0.978723 (-3600 6275);
PAINT WHITE (-3600 6275);
DISPLAY INVISIBLE (-3600 6275);
FORCEPROP 1 LAST PART_NUMBER TMP_QCS21002FB24
J 0
(-3610 5975);
DISPLAY 0.489362 (-3610 5975);
PAINT SKYBLUE (-3610 5975);
DISPLAY INVISIBLE (-3610 5975);
FORCEADD Q_RES..2
(-3450 4700);
FORCEPROP 1 LAST LOCATION R5008
J 0
(-3405 4825);
DISPLAY 0.489362 (-3405 4825);
PAINT SKYBLUE (-3405 4825);
FORCEPROP 0 LAST $SEC 1
J 0
(-3400 4850);
DISPLAY 0.680851 (-3400 4850);
PAINT MONO (-3400 4850);
DISPLAY INVISIBLE (-3400 4850);
FORCEPROP 0 LAST CDS_SEC 1
J 0
(-3400 4850);
DISPLAY 0.680851 (-3400 4850);
DISPLAY INVISIBLE (-3400 4850);
FORCEPROP 1 LASTPIN (-3450 4800) $PN 1
J 0
(-3445 4762);
DISPLAY 0.787234 (-3445 4762);
PAINT MONO (-3445 4762);
FORCEPROP 1 LASTPIN (-3450 4600) $PN 2
J 0
(-3445 4610);
DISPLAY 0.787234 (-3445 4610);
PAINT MONO (-3445 4610);
FORCEPROP 1 LAST PACK_TYPE 0402LF
J 0
(-3400 4575);
DISPLAY 0.489362 (-3400 4575);
PAINT SKYBLUE (-3400 4575);
FORCEPROP 1 LAST VALUE 1K
J 0
(-3405 4775);
DISPLAY 0.489362 (-3405 4775);
PAINT SKYBLUE (-3405 4775);
FORCEPROP 1 LAST TOLERANCE 1%
J 0
(-3405 4725);
DISPLAY 0.489362 (-3405 4725);
PAINT SKYBLUE (-3405 4725);
FORCEPROP 1 LAST WATTAGE 1/16W
J 0
(-3410 4675);
DISPLAY 0.489362 (-3410 4675);
PAINT SKYBLUE (-3410 4675);
FORCEPROP 1 LAST MATERIAL CHIP
J 0
(-3410 4625);
DISPLAY 0.489362 (-3410 4625);
PAINT SKYBLUE (-3410 4625);
FORCEPROP 1 LAST PART_NUMBER TMP_QCS21002FB24
J 0
(-3410 4575);
DISPLAY 0.489362 (-3410 4575);
PAINT SKYBLUE (-3410 4575);
DISPLAY INVISIBLE (-3410 4575);
FORCEPROP 1 LAST PATH I148
J 0
(-3400 4875);
DISPLAY 0.978723 (-3400 4875);
PAINT WHITE (-3400 4875);
DISPLAY INVISIBLE (-3400 4875);
FORCEPROP 2 LAST CDS_LIB pure_quanta
J 0
(-3450 4700);
DISPLAY INVISIBLE (-3450 4700);
FORCEADD VCC_CORE..1
(-3450 4975);
FORCEPROP 3 LASTPIN (-3450 4925) SIG_NAME PVDD11_S3_P0\g
J 0
(-3440 4935);
DISPLAY 0.659574 (-3440 4935);
PAINT MONO (-3440 4935);
DISPLAY INVISIBLE (-3440 4935);
FORCEPROP 1 LAST HDL_POWER PVDD11_S3_P0
J 1
(-3450 5025);
DISPLAY 0.489362 (-3450 5025);
PAINT GREEN (-3450 5025);
FORCEPROP 1 LAST PATH I149
J 0
(-3400 5000);
DISPLAY 0.872340 (-3400 5000);
PAINT AQUA (-3400 5000);
DISPLAY INVISIBLE (-3400 5000);
FORCEPROP 2 LAST CDS_LIB pure_quanta_power
J 0
(-3450 4975);
DISPLAY INVISIBLE (-3450 4975);
FORCEADD OFFPAGE..1
(-6025 5675);
FORCEPROP 2 LAST $XR0 117 
J 0
(-6307 5675);
DISPLAY 0.638298 (-6307 5675);
PAINT MONO (-6307 5675);
FORCEPROP 2 LAST PATH I15
J 0
(-5975 5750);
DISPLAY 1.021277 (-5975 5750);
DISPLAY INVISIBLE (-5975 5750);
FORCEPROP 1 LAST COMMENT_BODY TRUE
J 0
(-5900 5575);
DISPLAY 0.872340 (-5900 5575);
PAINT GREEN (-5900 5575);
DISPLAY INVISIBLE (-5900 5575);
FORCEPROP 1 LAST OFFPAGE TRUE
J 0
(-5700 5550);
DISPLAY 0.872340 (-5700 5550);
PAINT GREEN (-5700 5550);
DISPLAY INVISIBLE (-5700 5550);
FORCEPROP 2 LAST CDS_LIB standard
J 0
(-6025 5675);
DISPLAY INVISIBLE (-6025 5675);
FORCEADD Q_RES..2
(-3650 4700);
FORCEPROP 1 LAST LOCATION R5009
J 0
(-3605 4825);
DISPLAY 0.489362 (-3605 4825);
PAINT SKYBLUE (-3605 4825);
FORCEPROP 0 LAST $SEC 1
J 0
(-3600 4850);
DISPLAY 0.680851 (-3600 4850);
PAINT MONO (-3600 4850);
DISPLAY INVISIBLE (-3600 4850);
FORCEPROP 0 LAST CDS_SEC 1
J 0
(-3600 4850);
DISPLAY 0.680851 (-3600 4850);
DISPLAY INVISIBLE (-3600 4850);
FORCEPROP 1 LASTPIN (-3650 4800) $PN 1
J 0
(-3645 4762);
DISPLAY 0.787234 (-3645 4762);
PAINT MONO (-3645 4762);
FORCEPROP 1 LASTPIN (-3650 4600) $PN 2
J 0
(-3645 4610);
DISPLAY 0.787234 (-3645 4610);
PAINT MONO (-3645 4610);
FORCEPROP 1 LAST TOLERANCE 1%
J 0
(-3605 4725);
DISPLAY 0.489362 (-3605 4725);
PAINT SKYBLUE (-3605 4725);
FORCEPROP 1 LAST VALUE 1K
J 0
(-3605 4775);
DISPLAY 0.489362 (-3605 4775);
PAINT SKYBLUE (-3605 4775);
FORCEPROP 1 LAST PACK_TYPE 0402LF
J 0
(-3600 4575);
DISPLAY 0.489362 (-3600 4575);
PAINT SKYBLUE (-3600 4575);
FORCEPROP 1 LAST WATTAGE 1/16W
J 0
(-3610 4675);
DISPLAY 0.489362 (-3610 4675);
PAINT SKYBLUE (-3610 4675);
FORCEPROP 1 LAST MATERIAL CHIP
J 0
(-3610 4625);
DISPLAY 0.489362 (-3610 4625);
PAINT SKYBLUE (-3610 4625);
FORCEPROP 2 LAST CDS_LIB pure_quanta
J 0
(-3650 4700);
DISPLAY INVISIBLE (-3650 4700);
FORCEPROP 1 LAST PATH I150
J 0
(-3600 4875);
DISPLAY 0.978723 (-3600 4875);
PAINT WHITE (-3600 4875);
DISPLAY INVISIBLE (-3600 4875);
FORCEPROP 1 LAST PART_NUMBER TMP_QCS21002FB24
J 0
(-3610 4575);
DISPLAY 0.489362 (-3610 4575);
PAINT SKYBLUE (-3610 4575);
DISPLAY INVISIBLE (-3610 4575);
FORCEADD Q_RES..2
(-3450 3175);
FORCEPROP 1 LAST LOCATION R5010
J 0
(-3405 3300);
DISPLAY 0.489362 (-3405 3300);
PAINT SKYBLUE (-3405 3300);
FORCEPROP 0 LAST $SEC 1
J 0
(-3400 3325);
DISPLAY 0.680851 (-3400 3325);
PAINT MONO (-3400 3325);
DISPLAY INVISIBLE (-3400 3325);
FORCEPROP 0 LAST CDS_SEC 1
J 0
(-3400 3325);
DISPLAY 0.680851 (-3400 3325);
DISPLAY INVISIBLE (-3400 3325);
FORCEPROP 1 LASTPIN (-3450 3275) $PN 1
J 0
(-3445 3237);
DISPLAY 0.787234 (-3445 3237);
PAINT MONO (-3445 3237);
FORCEPROP 1 LASTPIN (-3450 3075) $PN 2
J 0
(-3445 3085);
DISPLAY 0.787234 (-3445 3085);
PAINT MONO (-3445 3085);
FORCEPROP 1 LAST VALUE 1K
J 0
(-3405 3250);
DISPLAY 0.489362 (-3405 3250);
PAINT SKYBLUE (-3405 3250);
FORCEPROP 1 LAST PACK_TYPE 0402LF
J 0
(-3400 3050);
DISPLAY 0.489362 (-3400 3050);
PAINT SKYBLUE (-3400 3050);
FORCEPROP 1 LAST TOLERANCE 1%
J 0
(-3405 3200);
DISPLAY 0.489362 (-3405 3200);
PAINT SKYBLUE (-3405 3200);
FORCEPROP 1 LAST WATTAGE 1/16W
J 0
(-3410 3150);
DISPLAY 0.489362 (-3410 3150);
PAINT SKYBLUE (-3410 3150);
FORCEPROP 1 LAST MATERIAL CHIP
J 0
(-3410 3100);
DISPLAY 0.489362 (-3410 3100);
PAINT SKYBLUE (-3410 3100);
FORCEPROP 1 LAST PART_NUMBER TMP_QCS21002FB24
J 0
(-3410 3050);
DISPLAY 0.489362 (-3410 3050);
PAINT SKYBLUE (-3410 3050);
DISPLAY INVISIBLE (-3410 3050);
FORCEPROP 1 LAST PATH I151
J 0
(-3400 3350);
DISPLAY 0.978723 (-3400 3350);
PAINT WHITE (-3400 3350);
DISPLAY INVISIBLE (-3400 3350);
FORCEPROP 2 LAST CDS_LIB pure_quanta
J 0
(-3450 3175);
DISPLAY INVISIBLE (-3450 3175);
FORCEADD Q_RES..2
(-3650 3175);
FORCEPROP 1 LAST LOCATION R5011
J 0
(-3605 3300);
DISPLAY 0.489362 (-3605 3300);
PAINT SKYBLUE (-3605 3300);
FORCEPROP 0 LAST $SEC 1
J 0
(-3600 3325);
DISPLAY 0.680851 (-3600 3325);
PAINT MONO (-3600 3325);
DISPLAY INVISIBLE (-3600 3325);
FORCEPROP 0 LAST CDS_SEC 1
J 0
(-3600 3325);
DISPLAY 0.680851 (-3600 3325);
DISPLAY INVISIBLE (-3600 3325);
FORCEPROP 1 LASTPIN (-3650 3275) $PN 1
J 0
(-3645 3237);
DISPLAY 0.787234 (-3645 3237);
PAINT MONO (-3645 3237);
FORCEPROP 1 LASTPIN (-3650 3075) $PN 2
J 0
(-3645 3085);
DISPLAY 0.787234 (-3645 3085);
PAINT MONO (-3645 3085);
FORCEPROP 1 LAST TOLERANCE 1%
J 0
(-3605 3200);
DISPLAY 0.489362 (-3605 3200);
PAINT SKYBLUE (-3605 3200);
FORCEPROP 1 LAST VALUE 1K
J 0
(-3605 3250);
DISPLAY 0.489362 (-3605 3250);
PAINT SKYBLUE (-3605 3250);
FORCEPROP 1 LAST PACK_TYPE 0402LF
J 0
(-3600 3050);
DISPLAY 0.489362 (-3600 3050);
PAINT SKYBLUE (-3600 3050);
FORCEPROP 1 LAST WATTAGE 1/16W
J 0
(-3610 3150);
DISPLAY 0.489362 (-3610 3150);
PAINT SKYBLUE (-3610 3150);
FORCEPROP 1 LAST MATERIAL CHIP
J 0
(-3610 3100);
DISPLAY 0.489362 (-3610 3100);
PAINT SKYBLUE (-3610 3100);
FORCEPROP 1 LAST PART_NUMBER TMP_QCS21002FB24
J 0
(-3610 3050);
DISPLAY 0.489362 (-3610 3050);
PAINT SKYBLUE (-3610 3050);
DISPLAY INVISIBLE (-3610 3050);
FORCEPROP 1 LAST PATH I152
J 0
(-3600 3350);
DISPLAY 0.978723 (-3600 3350);
PAINT WHITE (-3600 3350);
DISPLAY INVISIBLE (-3600 3350);
FORCEPROP 2 LAST CDS_LIB pure_quanta
J 0
(-3650 3175);
DISPLAY INVISIBLE (-3650 3175);
FORCEADD VCC_CORE..1
(-3450 3450);
FORCEPROP 3 LASTPIN (-3450 3400) SIG_NAME PVDD11_S3_P1\g
J 0
(-3440 3410);
DISPLAY 0.659574 (-3440 3410);
PAINT MONO (-3440 3410);
DISPLAY INVISIBLE (-3440 3410);
FORCEPROP 1 LAST HDL_POWER PVDD11_S3_P1
J 1
(-3450 3500);
DISPLAY 0.489362 (-3450 3500);
PAINT GREEN (-3450 3500);
FORCEPROP 2 LAST CDS_LIB pure_quanta_power
J 0
(-3450 3450);
DISPLAY INVISIBLE (-3450 3450);
FORCEPROP 1 LAST PATH I153
J 0
(-3400 3475);
DISPLAY 0.872340 (-3400 3475);
PAINT AQUA (-3400 3475);
DISPLAY INVISIBLE (-3400 3475);
FORCEADD Q_RES..2
(-3650 1725);
FORCEPROP 1 LAST LOCATION R5013
J 0
(-3605 1850);
DISPLAY 0.489362 (-3605 1850);
PAINT SKYBLUE (-3605 1850);
FORCEPROP 0 LAST $SEC 1
J 0
(-3600 1875);
DISPLAY 0.680851 (-3600 1875);
PAINT MONO (-3600 1875);
DISPLAY INVISIBLE (-3600 1875);
FORCEPROP 0 LAST CDS_SEC 1
J 0
(-3600 1875);
DISPLAY 0.680851 (-3600 1875);
DISPLAY INVISIBLE (-3600 1875);
FORCEPROP 1 LASTPIN (-3650 1825) $PN 1
J 0
(-3645 1787);
DISPLAY 0.787234 (-3645 1787);
PAINT MONO (-3645 1787);
FORCEPROP 1 LASTPIN (-3650 1625) $PN 2
J 0
(-3645 1635);
DISPLAY 0.787234 (-3645 1635);
PAINT MONO (-3645 1635);
FORCEPROP 1 LAST VALUE 1K
J 0
(-3605 1800);
DISPLAY 0.489362 (-3605 1800);
PAINT SKYBLUE (-3605 1800);
FORCEPROP 1 LAST TOLERANCE 1%
J 0
(-3605 1750);
DISPLAY 0.489362 (-3605 1750);
PAINT SKYBLUE (-3605 1750);
FORCEPROP 1 LAST WATTAGE 1/16W
J 0
(-3610 1700);
DISPLAY 0.489362 (-3610 1700);
PAINT SKYBLUE (-3610 1700);
FORCEPROP 1 LAST PACK_TYPE 0402LF
J 0
(-3600 1600);
DISPLAY 0.489362 (-3600 1600);
PAINT SKYBLUE (-3600 1600);
FORCEPROP 1 LAST MATERIAL CHIP
J 0
(-3610 1650);
DISPLAY 0.489362 (-3610 1650);
PAINT SKYBLUE (-3610 1650);
FORCEPROP 2 LAST CDS_LIB pure_quanta
J 0
(-3650 1725);
DISPLAY INVISIBLE (-3650 1725);
FORCEPROP 1 LAST PATH I154
J 0
(-3600 1900);
DISPLAY 0.978723 (-3600 1900);
PAINT WHITE (-3600 1900);
DISPLAY INVISIBLE (-3600 1900);
FORCEPROP 1 LAST PART_NUMBER TMP_QCS21002FB24
J 0
(-3610 1600);
DISPLAY 0.489362 (-3610 1600);
PAINT SKYBLUE (-3610 1600);
DISPLAY INVISIBLE (-3610 1600);
FORCEADD VCC_CORE..1
(-3450 2000);
FORCEPROP 3 LASTPIN (-3450 1950) SIG_NAME PVDD11_S3_P1\g
J 0
(-3440 1960);
DISPLAY 0.659574 (-3440 1960);
PAINT MONO (-3440 1960);
DISPLAY INVISIBLE (-3440 1960);
FORCEPROP 1 LAST HDL_POWER PVDD11_S3_P1
J 1
(-3450 2050);
DISPLAY 0.489362 (-3450 2050);
PAINT GREEN (-3450 2050);
FORCEPROP 1 LAST PATH I155
J 0
(-3400 2025);
DISPLAY 0.872340 (-3400 2025);
PAINT AQUA (-3400 2025);
DISPLAY INVISIBLE (-3400 2025);
FORCEPROP 2 LAST CDS_LIB pure_quanta_power
J 0
(-3450 2000);
DISPLAY INVISIBLE (-3450 2000);
FORCEADD Q_RES..2
(-3450 1725);
FORCEPROP 1 LAST LOCATION R5012
J 0
(-3405 1850);
DISPLAY 0.489362 (-3405 1850);
PAINT SKYBLUE (-3405 1850);
FORCEPROP 0 LAST $SEC 1
J 0
(-3400 1875);
DISPLAY 0.680851 (-3400 1875);
PAINT MONO (-3400 1875);
DISPLAY INVISIBLE (-3400 1875);
FORCEPROP 0 LAST CDS_SEC 1
J 0
(-3400 1875);
DISPLAY 0.680851 (-3400 1875);
DISPLAY INVISIBLE (-3400 1875);
FORCEPROP 1 LASTPIN (-3450 1825) $PN 1
J 0
(-3445 1787);
DISPLAY 0.787234 (-3445 1787);
PAINT MONO (-3445 1787);
FORCEPROP 1 LASTPIN (-3450 1625) $PN 2
J 0
(-3445 1635);
DISPLAY 0.787234 (-3445 1635);
PAINT MONO (-3445 1635);
FORCEPROP 1 LAST TOLERANCE 1%
J 0
(-3405 1750);
DISPLAY 0.489362 (-3405 1750);
PAINT SKYBLUE (-3405 1750);
FORCEPROP 1 LAST VALUE 1K
J 0
(-3405 1800);
DISPLAY 0.489362 (-3405 1800);
PAINT SKYBLUE (-3405 1800);
FORCEPROP 1 LAST WATTAGE 1/16W
J 0
(-3410 1700);
DISPLAY 0.489362 (-3410 1700);
PAINT SKYBLUE (-3410 1700);
FORCEPROP 1 LAST PACK_TYPE 0402LF
J 0
(-3400 1600);
DISPLAY 0.489362 (-3400 1600);
PAINT SKYBLUE (-3400 1600);
FORCEPROP 1 LAST MATERIAL CHIP
J 0
(-3410 1650);
DISPLAY 0.489362 (-3410 1650);
PAINT SKYBLUE (-3410 1650);
FORCEPROP 2 LAST CDS_LIB pure_quanta
J 0
(-3450 1725);
DISPLAY INVISIBLE (-3450 1725);
FORCEPROP 1 LAST PATH I156
J 0
(-3400 1900);
DISPLAY 0.978723 (-3400 1900);
PAINT WHITE (-3400 1900);
DISPLAY INVISIBLE (-3400 1900);
FORCEPROP 1 LAST PART_NUMBER TMP_QCS21002FB24
J 0
(-3410 1600);
DISPLAY 0.489362 (-3410 1600);
PAINT SKYBLUE (-3410 1600);
DISPLAY INVISIBLE (-3410 1600);
FORCEADD Q_RES..2
(-5650 6175);
FORCEPROP 1 LAST LOCATION R5015
J 0
(-5605 6300);
DISPLAY 0.489362 (-5605 6300);
PAINT SKYBLUE (-5605 6300);
FORCEPROP 0 LAST $SEC 1
J 0
(-5600 6325);
DISPLAY 0.680851 (-5600 6325);
PAINT MONO (-5600 6325);
DISPLAY INVISIBLE (-5600 6325);
FORCEPROP 0 LAST CDS_SEC 1
J 0
(-5600 6325);
DISPLAY 0.680851 (-5600 6325);
DISPLAY INVISIBLE (-5600 6325);
FORCEPROP 1 LASTPIN (-5650 6275) $PN 1
J 0
(-5645 6237);
DISPLAY 0.787234 (-5645 6237);
PAINT MONO (-5645 6237);
FORCEPROP 1 LASTPIN (-5650 6075) $PN 2
J 0
(-5645 6085);
DISPLAY 0.787234 (-5645 6085);
PAINT MONO (-5645 6085);
FORCEPROP 1 LAST VALUE 1K
J 0
(-5605 6250);
DISPLAY 0.489362 (-5605 6250);
PAINT SKYBLUE (-5605 6250);
FORCEPROP 1 LAST TOLERANCE 1%
J 0
(-5605 6200);
DISPLAY 0.489362 (-5605 6200);
PAINT SKYBLUE (-5605 6200);
FORCEPROP 1 LAST WATTAGE 1/16W
J 0
(-5610 6150);
DISPLAY 0.489362 (-5610 6150);
PAINT SKYBLUE (-5610 6150);
FORCEPROP 1 LAST PACK_TYPE 0402LF
J 0
(-5600 6050);
DISPLAY 0.489362 (-5600 6050);
PAINT SKYBLUE (-5600 6050);
FORCEPROP 1 LAST MATERIAL EMPTY
J 0
(-5610 6100);
DISPLAY 0.489362 (-5610 6100);
PAINT RED (-5610 6100);
FORCEPROP 1 LAST PART_NUMBER TMP_QCS21002FB24
J 0
(-5610 6050);
DISPLAY 0.489362 (-5610 6050);
PAINT SKYBLUE (-5610 6050);
DISPLAY INVISIBLE (-5610 6050);
FORCEPROP 1 LAST PATH I157
J 0
(-5600 6350);
DISPLAY 0.978723 (-5600 6350);
PAINT WHITE (-5600 6350);
DISPLAY INVISIBLE (-5600 6350);
FORCEPROP 2 LAST CDS_LIB pure_quanta
J 0
(-5650 6175);
DISPLAY INVISIBLE (-5650 6175);
FORCEADD VCC_CORE..1
(-5450 6475);
FORCEPROP 3 LASTPIN (-5450 6425) SIG_NAME PVDD11_S3_P0\g
J 0
(-5440 6435);
DISPLAY 0.659574 (-5440 6435);
PAINT MONO (-5440 6435);
DISPLAY INVISIBLE (-5440 6435);
FORCEPROP 1 LAST HDL_POWER PVDD11_S3_P0
J 1
(-5450 6525);
DISPLAY 0.489362 (-5450 6525);
PAINT GREEN (-5450 6525);
FORCEPROP 2 LAST CDS_LIB pure_quanta_power
J 0
(-5450 6475);
DISPLAY INVISIBLE (-5450 6475);
FORCEPROP 1 LAST PATH I158
J 0
(-5400 6500);
DISPLAY 0.872340 (-5400 6500);
PAINT AQUA (-5400 6500);
DISPLAY INVISIBLE (-5400 6500);
FORCEADD Q_RES..2
(-5450 6175);
FORCEPROP 1 LAST LOCATION R5014
J 0
(-5405 6300);
DISPLAY 0.489362 (-5405 6300);
PAINT SKYBLUE (-5405 6300);
FORCEPROP 0 LAST $SEC 1
J 0
(-5400 6325);
DISPLAY 0.680851 (-5400 6325);
PAINT MONO (-5400 6325);
DISPLAY INVISIBLE (-5400 6325);
FORCEPROP 0 LAST CDS_SEC 1
J 0
(-5400 6325);
DISPLAY 0.680851 (-5400 6325);
DISPLAY INVISIBLE (-5400 6325);
FORCEPROP 1 LASTPIN (-5450 6275) $PN 1
J 0
(-5445 6237);
DISPLAY 0.787234 (-5445 6237);
PAINT MONO (-5445 6237);
FORCEPROP 1 LASTPIN (-5450 6075) $PN 2
J 0
(-5445 6085);
DISPLAY 0.787234 (-5445 6085);
PAINT MONO (-5445 6085);
FORCEPROP 1 LAST WATTAGE 1/16W
J 0
(-5410 6150);
DISPLAY 0.489362 (-5410 6150);
PAINT SKYBLUE (-5410 6150);
FORCEPROP 1 LAST VALUE 1K
J 0
(-5405 6250);
DISPLAY 0.489362 (-5405 6250);
PAINT SKYBLUE (-5405 6250);
FORCEPROP 1 LAST MATERIAL EMPTY
J 0
(-5410 6100);
DISPLAY 0.489362 (-5410 6100);
PAINT RED (-5410 6100);
FORCEPROP 1 LAST TOLERANCE 1%
J 0
(-5405 6200);
DISPLAY 0.489362 (-5405 6200);
PAINT SKYBLUE (-5405 6200);
FORCEPROP 1 LAST PACK_TYPE 0402LF
J 0
(-5400 6050);
DISPLAY 0.489362 (-5400 6050);
PAINT SKYBLUE (-5400 6050);
FORCEPROP 1 LAST PART_NUMBER TMP_QCS21002FB24
J 0
(-5410 6050);
DISPLAY 0.489362 (-5410 6050);
PAINT SKYBLUE (-5410 6050);
DISPLAY INVISIBLE (-5410 6050);
FORCEPROP 1 LAST PATH I159
J 0
(-5400 6350);
DISPLAY 0.978723 (-5400 6350);
PAINT WHITE (-5400 6350);
DISPLAY INVISIBLE (-5400 6350);
FORCEPROP 2 LAST CDS_LIB pure_quanta
J 0
(-5450 6175);
DISPLAY INVISIBLE (-5450 6175);
FORCEADD VCC_CORE..1
(-5450 4900);
FORCEPROP 3 LASTPIN (-5450 4850) SIG_NAME PVDD11_S3_P0\g
J 0
(-5440 4860);
DISPLAY 0.659574 (-5440 4860);
PAINT MONO (-5440 4860);
DISPLAY INVISIBLE (-5440 4860);
FORCEPROP 1 LAST HDL_POWER PVDD11_S3_P0
J 1
(-5450 4950);
DISPLAY 0.489362 (-5450 4950);
PAINT GREEN (-5450 4950);
FORCEPROP 2 LAST CDS_LIB pure_quanta_power
J 0
(-5450 4900);
DISPLAY INVISIBLE (-5450 4900);
FORCEPROP 1 LAST PATH I160
J 0
(-5400 4925);
DISPLAY 0.872340 (-5400 4925);
PAINT AQUA (-5400 4925);
DISPLAY INVISIBLE (-5400 4925);
FORCEADD Q_RES..2
(-5650 4700);
FORCEPROP 1 LAST LOCATION R5017
J 0
(-5605 4825);
DISPLAY 0.489362 (-5605 4825);
PAINT SKYBLUE (-5605 4825);
FORCEPROP 0 LAST $SEC 1
J 0
(-5600 4850);
DISPLAY 0.680851 (-5600 4850);
PAINT MONO (-5600 4850);
DISPLAY INVISIBLE (-5600 4850);
FORCEPROP 0 LAST CDS_SEC 1
J 0
(-5600 4850);
DISPLAY 0.680851 (-5600 4850);
DISPLAY INVISIBLE (-5600 4850);
FORCEPROP 1 LASTPIN (-5650 4800) $PN 1
J 0
(-5645 4762);
DISPLAY 0.787234 (-5645 4762);
PAINT MONO (-5645 4762);
FORCEPROP 1 LASTPIN (-5650 4600) $PN 2
J 0
(-5645 4610);
DISPLAY 0.787234 (-5645 4610);
PAINT MONO (-5645 4610);
FORCEPROP 1 LAST WATTAGE 1/16W
J 0
(-5610 4675);
DISPLAY 0.489362 (-5610 4675);
PAINT SKYBLUE (-5610 4675);
FORCEPROP 1 LAST VALUE 1K
J 0
(-5605 4775);
DISPLAY 0.489362 (-5605 4775);
PAINT SKYBLUE (-5605 4775);
FORCEPROP 1 LAST TOLERANCE 1%
J 0
(-5605 4725);
DISPLAY 0.489362 (-5605 4725);
PAINT SKYBLUE (-5605 4725);
FORCEPROP 1 LAST PACK_TYPE 0402LF
J 0
(-5600 4575);
DISPLAY 0.489362 (-5600 4575);
PAINT SKYBLUE (-5600 4575);
FORCEPROP 1 LAST MATERIAL EMPTY
J 0
(-5610 4625);
DISPLAY 0.489362 (-5610 4625);
PAINT RED (-5610 4625);
FORCEPROP 1 LAST PART_NUMBER TMP_QCS21002FB24
J 0
(-5610 4575);
DISPLAY 0.489362 (-5610 4575);
PAINT SKYBLUE (-5610 4575);
DISPLAY INVISIBLE (-5610 4575);
FORCEPROP 1 LAST PATH I161
J 0
(-5600 4875);
DISPLAY 0.978723 (-5600 4875);
PAINT WHITE (-5600 4875);
DISPLAY INVISIBLE (-5600 4875);
FORCEPROP 2 LAST CDS_LIB pure_quanta
J 0
(-5650 4700);
DISPLAY INVISIBLE (-5650 4700);
FORCEADD Q_RES..2
(-5450 4700);
FORCEPROP 1 LAST LOCATION R5016
J 0
(-5405 4825);
DISPLAY 0.489362 (-5405 4825);
PAINT SKYBLUE (-5405 4825);
FORCEPROP 0 LAST $SEC 1
J 0
(-5400 4850);
DISPLAY 0.680851 (-5400 4850);
PAINT MONO (-5400 4850);
DISPLAY INVISIBLE (-5400 4850);
FORCEPROP 0 LAST CDS_SEC 1
J 0
(-5400 4850);
DISPLAY 0.680851 (-5400 4850);
DISPLAY INVISIBLE (-5400 4850);
FORCEPROP 1 LASTPIN (-5450 4800) $PN 1
J 0
(-5445 4762);
DISPLAY 0.787234 (-5445 4762);
PAINT MONO (-5445 4762);
FORCEPROP 1 LASTPIN (-5450 4600) $PN 2
J 0
(-5445 4610);
DISPLAY 0.787234 (-5445 4610);
PAINT MONO (-5445 4610);
FORCEPROP 1 LAST TOLERANCE 1%
J 0
(-5405 4725);
DISPLAY 0.489362 (-5405 4725);
PAINT SKYBLUE (-5405 4725);
FORCEPROP 1 LAST VALUE 1K
J 0
(-5405 4775);
DISPLAY 0.489362 (-5405 4775);
PAINT SKYBLUE (-5405 4775);
FORCEPROP 1 LAST PACK_TYPE 0402LF
J 0
(-5400 4575);
DISPLAY 0.489362 (-5400 4575);
PAINT SKYBLUE (-5400 4575);
FORCEPROP 1 LAST MATERIAL EMPTY
J 0
(-5410 4625);
DISPLAY 0.489362 (-5410 4625);
PAINT RED (-5410 4625);
FORCEPROP 1 LAST WATTAGE 1/16W
J 0
(-5410 4675);
DISPLAY 0.489362 (-5410 4675);
PAINT SKYBLUE (-5410 4675);
FORCEPROP 1 LAST PART_NUMBER TMP_QCS21002FB24
J 0
(-5410 4575);
DISPLAY 0.489362 (-5410 4575);
PAINT SKYBLUE (-5410 4575);
DISPLAY INVISIBLE (-5410 4575);
FORCEPROP 1 LAST PATH I162
J 0
(-5400 4875);
DISPLAY 0.978723 (-5400 4875);
PAINT WHITE (-5400 4875);
DISPLAY INVISIBLE (-5400 4875);
FORCEPROP 2 LAST CDS_LIB pure_quanta
J 0
(-5450 4700);
DISPLAY INVISIBLE (-5450 4700);
FORCEADD Q_RES..2
(-5450 3175);
FORCEPROP 1 LAST LOCATION R5018
J 0
(-5405 3300);
DISPLAY 0.489362 (-5405 3300);
PAINT SKYBLUE (-5405 3300);
FORCEPROP 0 LAST $SEC 1
J 0
(-5400 3325);
DISPLAY 0.680851 (-5400 3325);
PAINT MONO (-5400 3325);
DISPLAY INVISIBLE (-5400 3325);
FORCEPROP 0 LAST CDS_SEC 1
J 0
(-5400 3325);
DISPLAY 0.680851 (-5400 3325);
DISPLAY INVISIBLE (-5400 3325);
FORCEPROP 1 LASTPIN (-5450 3275) $PN 1
J 0
(-5445 3237);
DISPLAY 0.787234 (-5445 3237);
PAINT MONO (-5445 3237);
FORCEPROP 1 LASTPIN (-5450 3075) $PN 2
J 0
(-5445 3085);
DISPLAY 0.787234 (-5445 3085);
PAINT MONO (-5445 3085);
FORCEPROP 1 LAST PACK_TYPE 0402LF
J 0
(-5400 3050);
DISPLAY 0.489362 (-5400 3050);
PAINT SKYBLUE (-5400 3050);
FORCEPROP 1 LAST VALUE 1K
J 0
(-5405 3250);
DISPLAY 0.489362 (-5405 3250);
PAINT SKYBLUE (-5405 3250);
FORCEPROP 1 LAST TOLERANCE 1%
J 0
(-5405 3200);
DISPLAY 0.489362 (-5405 3200);
PAINT SKYBLUE (-5405 3200);
FORCEPROP 1 LAST MATERIAL EMPTY
J 0
(-5410 3100);
DISPLAY 0.489362 (-5410 3100);
PAINT RED (-5410 3100);
FORCEPROP 1 LAST WATTAGE 1/16W
J 0
(-5410 3150);
DISPLAY 0.489362 (-5410 3150);
PAINT SKYBLUE (-5410 3150);
FORCEPROP 1 LAST PART_NUMBER TMP_QCS21002FB24
J 0
(-5410 3050);
DISPLAY 0.489362 (-5410 3050);
PAINT SKYBLUE (-5410 3050);
DISPLAY INVISIBLE (-5410 3050);
FORCEPROP 1 LAST PATH I163
J 0
(-5400 3350);
DISPLAY 0.978723 (-5400 3350);
PAINT WHITE (-5400 3350);
DISPLAY INVISIBLE (-5400 3350);
FORCEPROP 2 LAST CDS_LIB pure_quanta
J 0
(-5450 3175);
DISPLAY INVISIBLE (-5450 3175);
FORCEADD Q_RES..2
(-5650 3175);
FORCEPROP 1 LAST LOCATION R5019
J 0
(-5605 3300);
DISPLAY 0.489362 (-5605 3300);
PAINT SKYBLUE (-5605 3300);
FORCEPROP 0 LAST $SEC 1
J 0
(-5600 3325);
DISPLAY 0.680851 (-5600 3325);
PAINT MONO (-5600 3325);
DISPLAY INVISIBLE (-5600 3325);
FORCEPROP 0 LAST CDS_SEC 1
J 0
(-5600 3325);
DISPLAY 0.680851 (-5600 3325);
DISPLAY INVISIBLE (-5600 3325);
FORCEPROP 1 LASTPIN (-5650 3275) $PN 1
J 0
(-5645 3237);
DISPLAY 0.787234 (-5645 3237);
PAINT MONO (-5645 3237);
FORCEPROP 1 LASTPIN (-5650 3075) $PN 2
J 0
(-5645 3085);
DISPLAY 0.787234 (-5645 3085);
PAINT MONO (-5645 3085);
FORCEPROP 1 LAST PACK_TYPE 0402LF
J 0
(-5600 3050);
DISPLAY 0.489362 (-5600 3050);
PAINT SKYBLUE (-5600 3050);
FORCEPROP 1 LAST VALUE 1K
J 0
(-5605 3250);
DISPLAY 0.489362 (-5605 3250);
PAINT SKYBLUE (-5605 3250);
FORCEPROP 1 LAST TOLERANCE 1%
J 0
(-5605 3200);
DISPLAY 0.489362 (-5605 3200);
PAINT SKYBLUE (-5605 3200);
FORCEPROP 1 LAST WATTAGE 1/16W
J 0
(-5610 3150);
DISPLAY 0.489362 (-5610 3150);
PAINT SKYBLUE (-5610 3150);
FORCEPROP 1 LAST MATERIAL EMPTY
J 0
(-5610 3100);
DISPLAY 0.489362 (-5610 3100);
PAINT RED (-5610 3100);
FORCEPROP 1 LAST PART_NUMBER TMP_QCS21002FB24
J 0
(-5610 3050);
DISPLAY 0.489362 (-5610 3050);
PAINT SKYBLUE (-5610 3050);
DISPLAY INVISIBLE (-5610 3050);
FORCEPROP 1 LAST PATH I164
J 0
(-5600 3350);
DISPLAY 0.978723 (-5600 3350);
PAINT WHITE (-5600 3350);
DISPLAY INVISIBLE (-5600 3350);
FORCEPROP 2 LAST CDS_LIB pure_quanta
J 0
(-5650 3175);
DISPLAY INVISIBLE (-5650 3175);
FORCEADD VCC_CORE..1
(-5450 3375);
FORCEPROP 3 LASTPIN (-5450 3325) SIG_NAME PVDD11_S3_P1\g
J 0
(-5440 3335);
DISPLAY 0.659574 (-5440 3335);
PAINT MONO (-5440 3335);
DISPLAY INVISIBLE (-5440 3335);
FORCEPROP 1 LAST HDL_POWER PVDD11_S3_P1
J 1
(-5450 3425);
DISPLAY 0.489362 (-5450 3425);
PAINT GREEN (-5450 3425);
FORCEPROP 2 LAST CDS_LIB pure_quanta_power
J 0
(-5450 3375);
DISPLAY INVISIBLE (-5450 3375);
FORCEPROP 1 LAST PATH I165
J 0
(-5400 3400);
DISPLAY 0.872340 (-5400 3400);
PAINT AQUA (-5400 3400);
DISPLAY INVISIBLE (-5400 3400);
FORCEADD Q_RES..2
(-5650 1725);
FORCEPROP 1 LAST LOCATION R5021
J 0
(-5605 1850);
DISPLAY 0.489362 (-5605 1850);
PAINT SKYBLUE (-5605 1850);
FORCEPROP 0 LAST $SEC 1
J 0
(-5600 1875);
DISPLAY 0.680851 (-5600 1875);
PAINT MONO (-5600 1875);
DISPLAY INVISIBLE (-5600 1875);
FORCEPROP 0 LAST CDS_SEC 1
J 0
(-5600 1875);
DISPLAY 0.680851 (-5600 1875);
DISPLAY INVISIBLE (-5600 1875);
FORCEPROP 1 LASTPIN (-5650 1825) $PN 1
J 0
(-5645 1787);
DISPLAY 0.787234 (-5645 1787);
PAINT MONO (-5645 1787);
FORCEPROP 1 LASTPIN (-5650 1625) $PN 2
J 0
(-5645 1635);
DISPLAY 0.787234 (-5645 1635);
PAINT MONO (-5645 1635);
FORCEPROP 1 LAST TOLERANCE 1%
J 0
(-5605 1750);
DISPLAY 0.489362 (-5605 1750);
PAINT SKYBLUE (-5605 1750);
FORCEPROP 1 LAST WATTAGE 1/16W
J 0
(-5610 1700);
DISPLAY 0.489362 (-5610 1700);
PAINT SKYBLUE (-5610 1700);
FORCEPROP 1 LAST VALUE 1K
J 0
(-5605 1800);
DISPLAY 0.489362 (-5605 1800);
PAINT SKYBLUE (-5605 1800);
FORCEPROP 1 LAST PACK_TYPE 0402LF
J 0
(-5600 1600);
DISPLAY 0.489362 (-5600 1600);
PAINT SKYBLUE (-5600 1600);
FORCEPROP 1 LAST MATERIAL EMPTY
J 0
(-5610 1650);
DISPLAY 0.489362 (-5610 1650);
PAINT RED (-5610 1650);
FORCEPROP 2 LAST CDS_LIB pure_quanta
J 0
(-5650 1725);
DISPLAY INVISIBLE (-5650 1725);
FORCEPROP 1 LAST PATH I166
J 0
(-5600 1900);
DISPLAY 0.978723 (-5600 1900);
PAINT WHITE (-5600 1900);
DISPLAY INVISIBLE (-5600 1900);
FORCEPROP 1 LAST PART_NUMBER TMP_QCS21002FB24
J 0
(-5610 1600);
DISPLAY 0.489362 (-5610 1600);
PAINT SKYBLUE (-5610 1600);
DISPLAY INVISIBLE (-5610 1600);
FORCEADD Q_RES..2
(-5450 1725);
FORCEPROP 1 LAST LOCATION R5020
J 0
(-5405 1850);
DISPLAY 0.489362 (-5405 1850);
PAINT SKYBLUE (-5405 1850);
FORCEPROP 0 LAST $SEC 1
J 0
(-5400 1875);
DISPLAY 0.680851 (-5400 1875);
PAINT MONO (-5400 1875);
DISPLAY INVISIBLE (-5400 1875);
FORCEPROP 0 LAST CDS_SEC 1
J 0
(-5400 1875);
DISPLAY 0.680851 (-5400 1875);
DISPLAY INVISIBLE (-5400 1875);
FORCEPROP 1 LASTPIN (-5450 1825) $PN 1
J 0
(-5445 1787);
DISPLAY 0.787234 (-5445 1787);
PAINT MONO (-5445 1787);
FORCEPROP 1 LASTPIN (-5450 1625) $PN 2
J 0
(-5445 1635);
DISPLAY 0.787234 (-5445 1635);
PAINT MONO (-5445 1635);
FORCEPROP 1 LAST TOLERANCE 1%
J 0
(-5405 1750);
DISPLAY 0.489362 (-5405 1750);
PAINT SKYBLUE (-5405 1750);
FORCEPROP 1 LAST VALUE 1K
J 0
(-5405 1800);
DISPLAY 0.489362 (-5405 1800);
PAINT SKYBLUE (-5405 1800);
FORCEPROP 1 LAST PACK_TYPE 0402LF
J 0
(-5400 1600);
DISPLAY 0.489362 (-5400 1600);
PAINT SKYBLUE (-5400 1600);
FORCEPROP 1 LAST MATERIAL EMPTY
J 0
(-5410 1650);
DISPLAY 0.489362 (-5410 1650);
PAINT RED (-5410 1650);
FORCEPROP 1 LAST WATTAGE 1/16W
J 0
(-5410 1700);
DISPLAY 0.489362 (-5410 1700);
PAINT SKYBLUE (-5410 1700);
FORCEPROP 2 LAST CDS_LIB pure_quanta
J 0
(-5450 1725);
DISPLAY INVISIBLE (-5450 1725);
FORCEPROP 1 LAST PATH I167
J 0
(-5400 1900);
DISPLAY 0.978723 (-5400 1900);
PAINT WHITE (-5400 1900);
DISPLAY INVISIBLE (-5400 1900);
FORCEPROP 1 LAST PART_NUMBER TMP_QCS21002FB24
J 0
(-5410 1600);
DISPLAY 0.489362 (-5410 1600);
PAINT SKYBLUE (-5410 1600);
DISPLAY INVISIBLE (-5410 1600);
FORCEADD VCC_CORE..1
(-5450 1925);
FORCEPROP 3 LASTPIN (-5450 1875) SIG_NAME PVDD11_S3_P1\g
J 0
(-5440 1885);
DISPLAY 0.659574 (-5440 1885);
PAINT MONO (-5440 1885);
DISPLAY INVISIBLE (-5440 1885);
FORCEPROP 1 LAST HDL_POWER PVDD11_S3_P1
J 1
(-5450 1975);
DISPLAY 0.489362 (-5450 1975);
PAINT GREEN (-5450 1975);
FORCEPROP 1 LAST PATH I168
J 0
(-5400 1950);
DISPLAY 0.872340 (-5400 1950);
PAINT AQUA (-5400 1950);
DISPLAY INVISIBLE (-5400 1950);
FORCEPROP 2 LAST CDS_LIB pure_quanta_power
J 0
(-5450 1925);
DISPLAY INVISIBLE (-5450 1925);
FORCEADD OFFPAGE..3
R 2
(-6000 4225);
FORCEPROP 2 LAST $XR0 117 
J 0
(-6280 4225);
DISPLAY 0.638298 (-6280 4225);
PAINT MONO (-6280 4225);
FORCEPROP 2 LAST PATH I19
J 0
(-5950 4300);
DISPLAY 1.021277 (-5950 4300);
DISPLAY INVISIBLE (-5950 4300);
FORCEPROP 1 LAST COMMENT_BODY TRUE
J 2
(-5950 4125);
DISPLAY 0.872340 (-5950 4125);
PAINT GREEN (-5950 4125);
DISPLAY INVISIBLE (-5950 4125);
FORCEPROP 1 LAST OFFPAGE TRUE
J 2
(-6325 4100);
DISPLAY 0.872340 (-6325 4100);
PAINT GREEN (-6325 4100);
DISPLAY INVISIBLE (-6325 4100);
FORCEPROP 2 LAST CDS_LIB standard
J 2
(-6000 4225);
DISPLAY INVISIBLE (-6000 4225);
FORCEADD OFFPAGE..1
(-6000 4275);
FORCEPROP 2 LAST $XR0 117 
J 0
(-6282 4275);
DISPLAY 0.638298 (-6282 4275);
PAINT MONO (-6282 4275);
FORCEPROP 2 LAST PATH I20
J 0
(-5950 4350);
DISPLAY 1.021277 (-5950 4350);
DISPLAY INVISIBLE (-5950 4350);
FORCEPROP 1 LAST COMMENT_BODY TRUE
J 0
(-5875 4175);
DISPLAY 0.872340 (-5875 4175);
PAINT GREEN (-5875 4175);
DISPLAY INVISIBLE (-5875 4175);
FORCEPROP 1 LAST OFFPAGE TRUE
J 0
(-5675 4150);
DISPLAY 0.872340 (-5675 4150);
PAINT GREEN (-5675 4150);
DISPLAY INVISIBLE (-5675 4150);
FORCEPROP 2 LAST CDS_LIB standard
J 0
(-6000 4275);
DISPLAY INVISIBLE (-6000 4275);
FORCEADD OFFPAGE..3
R 2
(-5925 1250);
FORCEPROP 2 LAST $XR0 117 
J 0
(-6235 1250);
DISPLAY 0.638298 (-6235 1250);
PAINT MONO (-6235 1250);
FORCEPROP 2 LAST PATH I26
J 0
(-5875 1325);
DISPLAY 1.021277 (-5875 1325);
DISPLAY INVISIBLE (-5875 1325);
FORCEPROP 1 LAST COMMENT_BODY TRUE
J 2
(-5875 1150);
DISPLAY 0.872340 (-5875 1150);
PAINT GREEN (-5875 1150);
DISPLAY INVISIBLE (-5875 1150);
FORCEPROP 1 LAST OFFPAGE TRUE
J 2
(-6250 1125);
DISPLAY 0.872340 (-6250 1125);
PAINT GREEN (-6250 1125);
DISPLAY INVISIBLE (-6250 1125);
FORCEPROP 2 LAST CDS_LIB standard
J 2
(-5925 1250);
DISPLAY INVISIBLE (-5925 1250);
FORCEADD OFFPAGE..3
R 2
(-6000 2700);
FORCEPROP 2 LAST $XR0 117 
J 0
(-6280 2700);
DISPLAY 0.638298 (-6280 2700);
PAINT MONO (-6280 2700);
FORCEPROP 2 LAST PATH I28
J 0
(-5950 2775);
DISPLAY 1.021277 (-5950 2775);
DISPLAY INVISIBLE (-5950 2775);
FORCEPROP 1 LAST COMMENT_BODY TRUE
J 2
(-5950 2600);
DISPLAY 0.872340 (-5950 2600);
PAINT GREEN (-5950 2600);
DISPLAY INVISIBLE (-5950 2600);
FORCEPROP 1 LAST OFFPAGE TRUE
J 2
(-6325 2575);
DISPLAY 0.872340 (-6325 2575);
PAINT GREEN (-6325 2575);
DISPLAY INVISIBLE (-6325 2575);
FORCEPROP 2 LAST CDS_LIB standard
J 2
(-6000 2700);
DISPLAY INVISIBLE (-6000 2700);
FORCEADD OFFPAGE..1
(-5925 1300);
FORCEPROP 2 LAST $XR0 117 
J 0
(-6177 1300);
DISPLAY 0.638298 (-6177 1300);
PAINT MONO (-6177 1300);
FORCEPROP 2 LAST PATH I29
J 0
(-5875 1375);
DISPLAY 1.021277 (-5875 1375);
DISPLAY INVISIBLE (-5875 1375);
FORCEPROP 1 LAST COMMENT_BODY TRUE
J 0
(-5800 1200);
DISPLAY 0.872340 (-5800 1200);
PAINT GREEN (-5800 1200);
DISPLAY INVISIBLE (-5800 1200);
FORCEPROP 1 LAST OFFPAGE TRUE
J 0
(-5600 1175);
DISPLAY 0.872340 (-5600 1175);
PAINT GREEN (-5600 1175);
DISPLAY INVISIBLE (-5600 1175);
FORCEPROP 2 LAST CDS_LIB standard
J 0
(-5925 1300);
DISPLAY INVISIBLE (-5925 1300);
FORCEADD OFFPAGE..1
(-6000 2750);
FORCEPROP 2 LAST $XR0 117 
J 0
(-6282 2750);
DISPLAY 0.638298 (-6282 2750);
PAINT MONO (-6282 2750);
FORCEPROP 2 LAST PATH I30
J 0
(-5950 2825);
DISPLAY 1.021277 (-5950 2825);
DISPLAY INVISIBLE (-5950 2825);
FORCEPROP 1 LAST COMMENT_BODY TRUE
J 0
(-5875 2650);
DISPLAY 0.872340 (-5875 2650);
PAINT GREEN (-5875 2650);
DISPLAY INVISIBLE (-5875 2650);
FORCEPROP 1 LAST OFFPAGE TRUE
J 0
(-5675 2625);
DISPLAY 0.872340 (-5675 2625);
PAINT GREEN (-5675 2625);
DISPLAY INVISIBLE (-5675 2625);
FORCEPROP 2 LAST CDS_LIB standard
J 0
(-6000 2750);
DISPLAY INVISIBLE (-6000 2750);
FORCEADD Q_RES..1
R 2
(-3150 5875);
FORCEPROP 1 LAST LOCATION R1297
J 2
(-3300 5875);
DISPLAY 0.489362 (-3300 5875);
PAINT SKYBLUE (-3300 5875);
FORCEPROP 0 LAST $SEC 1
J 0
(-3300 5925);
DISPLAY 0.680851 (-3300 5925);
PAINT MONO (-3300 5925);
DISPLAY INVISIBLE (-3300 5925);
FORCEPROP 0 LAST CDS_SEC 1
J 0
(-3300 5925);
DISPLAY 1.021277 (-3300 5925);
DISPLAY INVISIBLE (-3300 5925);
FORCEPROP 1 LASTPIN (-3050 5875) $PN 1
J 2
(-3062 5887);
DISPLAY 0.489362 (-3062 5887);
PAINT MONO (-3062 5887);
FORCEPROP 1 LASTPIN (-3250 5875) $PN 2
J 2
(-3212 5887);
DISPLAY 0.489362 (-3212 5887);
PAINT MONO (-3212 5887);
FORCEPROP 1 LAST VALUE 0
J 0
(-3050 5875);
DISPLAY 0.489362 (-3050 5875);
PAINT SKYBLUE (-3050 5875);
FORCEPROP 2 LAST CDS_LIB pure_quanta
J 0
(-3150 5875);
DISPLAY INVISIBLE (-3150 5875);
FORCEPROP 1 LAST PATH I31
J 2
(-3100 6025);
DISPLAY 0.978723 (-3100 6025);
PAINT WHITE (-3100 6025);
DISPLAY INVISIBLE (-3100 6025);
FORCEPROP 1 LAST WATTAGE 1/16W
J 0
(-3550 5800);
DISPLAY 0.489362 (-3550 5800);
PAINT SKYBLUE (-3550 5800);
DISPLAY INVISIBLE (-3550 5800);
FORCEPROP 1 LAST MATERIAL CHIP
J 2
(-3575 5800);
DISPLAY 0.489362 (-3575 5800);
PAINT SKYBLUE (-3575 5800);
DISPLAY INVISIBLE (-3575 5800);
FORCEPROP 1 LAST TOLERANCE 5%
J 2
(-3125 5800);
DISPLAY 0.489362 (-3125 5800);
PAINT SKYBLUE (-3125 5800);
DISPLAY INVISIBLE (-3125 5800);
FORCEPROP 1 LAST PART_NUMBER CS00002JB38
J 2
(-3175 5925);
DISPLAY 0.489362 (-3175 5925);
PAINT SKYBLUE (-3175 5925);
DISPLAY INVISIBLE (-3175 5925);
FORCEPROP 1 LAST PACK_TYPE 0402LF
J 2
(-3200 5800);
DISPLAY 0.489362 (-3200 5800);
PAINT SKYBLUE (-3200 5800);
DISPLAY INVISIBLE (-3200 5800);
FORCEADD Q_RES..1
R 2
(-3150 5825);
FORCEPROP 1 LAST LOCATION R1298
J 2
(-3300 5825);
DISPLAY 0.489362 (-3300 5825);
PAINT SKYBLUE (-3300 5825);
FORCEPROP 0 LAST $SEC 1
J 0
(-3300 5875);
DISPLAY 0.680851 (-3300 5875);
PAINT MONO (-3300 5875);
DISPLAY INVISIBLE (-3300 5875);
FORCEPROP 0 LAST CDS_SEC 1
J 0
(-3300 5875);
DISPLAY 1.021277 (-3300 5875);
DISPLAY INVISIBLE (-3300 5875);
FORCEPROP 1 LASTPIN (-3050 5825) $PN 1
J 2
(-3062 5837);
DISPLAY 0.489362 (-3062 5837);
PAINT MONO (-3062 5837);
FORCEPROP 1 LASTPIN (-3250 5825) $PN 2
J 2
(-3212 5837);
DISPLAY 0.489362 (-3212 5837);
PAINT MONO (-3212 5837);
FORCEPROP 1 LAST VALUE 0
J 0
(-3050 5825);
DISPLAY 0.489362 (-3050 5825);
PAINT SKYBLUE (-3050 5825);
FORCEPROP 2 LAST CDS_LIB pure_quanta
J 0
(-3150 5825);
DISPLAY INVISIBLE (-3150 5825);
FORCEPROP 1 LAST PATH I32
J 2
(-3100 5975);
DISPLAY 0.978723 (-3100 5975);
PAINT WHITE (-3100 5975);
DISPLAY INVISIBLE (-3100 5975);
FORCEPROP 1 LAST WATTAGE 1/16W
J 0
(-3550 5750);
DISPLAY 0.489362 (-3550 5750);
PAINT SKYBLUE (-3550 5750);
DISPLAY INVISIBLE (-3550 5750);
FORCEPROP 1 LAST MATERIAL CHIP
J 2
(-3575 5750);
DISPLAY 0.489362 (-3575 5750);
PAINT SKYBLUE (-3575 5750);
DISPLAY INVISIBLE (-3575 5750);
FORCEPROP 1 LAST TOLERANCE 5%
J 2
(-3125 5750);
DISPLAY 0.489362 (-3125 5750);
PAINT SKYBLUE (-3125 5750);
DISPLAY INVISIBLE (-3125 5750);
FORCEPROP 1 LAST PART_NUMBER CS00002JB38
J 2
(-3175 5875);
DISPLAY 0.489362 (-3175 5875);
PAINT SKYBLUE (-3175 5875);
DISPLAY INVISIBLE (-3175 5875);
FORCEPROP 1 LAST PACK_TYPE 0402LF
J 2
(-3200 5750);
DISPLAY 0.489362 (-3200 5750);
PAINT SKYBLUE (-3200 5750);
DISPLAY INVISIBLE (-3200 5750);
FORCEADD Q_RES..1
R 2
(-3150 4475);
FORCEPROP 1 LAST LOCATION R1299
J 2
(-3300 4475);
DISPLAY 0.489362 (-3300 4475);
PAINT SKYBLUE (-3300 4475);
FORCEPROP 0 LAST $SEC 1
J 0
(-3300 4525);
DISPLAY 0.680851 (-3300 4525);
PAINT MONO (-3300 4525);
DISPLAY INVISIBLE (-3300 4525);
FORCEPROP 0 LAST CDS_SEC 1
J 0
(-3300 4525);
DISPLAY 1.021277 (-3300 4525);
DISPLAY INVISIBLE (-3300 4525);
FORCEPROP 1 LASTPIN (-3050 4475) $PN 1
J 2
(-3062 4487);
DISPLAY 0.489362 (-3062 4487);
PAINT MONO (-3062 4487);
FORCEPROP 1 LASTPIN (-3250 4475) $PN 2
J 2
(-3212 4487);
DISPLAY 0.489362 (-3212 4487);
PAINT MONO (-3212 4487);
FORCEPROP 1 LAST VALUE 0
J 0
(-3050 4475);
DISPLAY 0.489362 (-3050 4475);
PAINT SKYBLUE (-3050 4475);
FORCEPROP 2 LAST CDS_LIB pure_quanta
J 0
(-3150 4475);
DISPLAY INVISIBLE (-3150 4475);
FORCEPROP 1 LAST PATH I33
J 2
(-3100 4625);
DISPLAY 0.978723 (-3100 4625);
PAINT WHITE (-3100 4625);
DISPLAY INVISIBLE (-3100 4625);
FORCEPROP 1 LAST WATTAGE 1/16W
J 0
(-3550 4400);
DISPLAY 0.489362 (-3550 4400);
PAINT SKYBLUE (-3550 4400);
DISPLAY INVISIBLE (-3550 4400);
FORCEPROP 1 LAST MATERIAL CHIP
J 2
(-3575 4400);
DISPLAY 0.489362 (-3575 4400);
PAINT SKYBLUE (-3575 4400);
DISPLAY INVISIBLE (-3575 4400);
FORCEPROP 1 LAST TOLERANCE 5%
J 2
(-3125 4400);
DISPLAY 0.489362 (-3125 4400);
PAINT SKYBLUE (-3125 4400);
DISPLAY INVISIBLE (-3125 4400);
FORCEPROP 1 LAST PART_NUMBER CS00002JB38
J 2
(-3175 4525);
DISPLAY 0.489362 (-3175 4525);
PAINT SKYBLUE (-3175 4525);
DISPLAY INVISIBLE (-3175 4525);
FORCEPROP 1 LAST PACK_TYPE 0402LF
J 2
(-3200 4400);
DISPLAY 0.489362 (-3200 4400);
PAINT SKYBLUE (-3200 4400);
DISPLAY INVISIBLE (-3200 4400);
FORCEADD Q_RES..1
R 2
(-3150 4425);
FORCEPROP 1 LAST LOCATION R1300
J 2
(-3300 4425);
DISPLAY 0.489362 (-3300 4425);
PAINT SKYBLUE (-3300 4425);
FORCEPROP 0 LAST $SEC 1
J 0
(-3300 4475);
DISPLAY 0.680851 (-3300 4475);
PAINT MONO (-3300 4475);
DISPLAY INVISIBLE (-3300 4475);
FORCEPROP 0 LAST CDS_SEC 1
J 0
(-3300 4475);
DISPLAY 1.021277 (-3300 4475);
DISPLAY INVISIBLE (-3300 4475);
FORCEPROP 1 LASTPIN (-3050 4425) $PN 1
J 2
(-3062 4437);
DISPLAY 0.489362 (-3062 4437);
PAINT MONO (-3062 4437);
FORCEPROP 1 LASTPIN (-3250 4425) $PN 2
J 2
(-3212 4437);
DISPLAY 0.489362 (-3212 4437);
PAINT MONO (-3212 4437);
FORCEPROP 1 LAST VALUE 0
J 0
(-3050 4425);
DISPLAY 0.489362 (-3050 4425);
PAINT SKYBLUE (-3050 4425);
FORCEPROP 2 LAST CDS_LIB pure_quanta
J 0
(-3150 4425);
DISPLAY INVISIBLE (-3150 4425);
FORCEPROP 1 LAST PATH I34
J 2
(-3100 4575);
DISPLAY 0.978723 (-3100 4575);
PAINT WHITE (-3100 4575);
DISPLAY INVISIBLE (-3100 4575);
FORCEPROP 1 LAST WATTAGE 1/16W
J 0
(-3550 4350);
DISPLAY 0.489362 (-3550 4350);
PAINT SKYBLUE (-3550 4350);
DISPLAY INVISIBLE (-3550 4350);
FORCEPROP 1 LAST MATERIAL CHIP
J 2
(-3575 4350);
DISPLAY 0.489362 (-3575 4350);
PAINT SKYBLUE (-3575 4350);
DISPLAY INVISIBLE (-3575 4350);
FORCEPROP 1 LAST TOLERANCE 5%
J 2
(-3125 4350);
DISPLAY 0.489362 (-3125 4350);
PAINT SKYBLUE (-3125 4350);
DISPLAY INVISIBLE (-3125 4350);
FORCEPROP 1 LAST PART_NUMBER CS00002JB38
J 2
(-3175 4475);
DISPLAY 0.489362 (-3175 4475);
PAINT SKYBLUE (-3175 4475);
DISPLAY INVISIBLE (-3175 4475);
FORCEPROP 1 LAST PACK_TYPE 0402LF
J 2
(-3200 4350);
DISPLAY 0.489362 (-3200 4350);
PAINT SKYBLUE (-3200 4350);
DISPLAY INVISIBLE (-3200 4350);
FORCEADD Q_RES..1
R 2
(-3200 2950);
FORCEPROP 1 LAST LOCATION R1293
J 2
(-3350 2950);
DISPLAY 0.489362 (-3350 2950);
PAINT SKYBLUE (-3350 2950);
FORCEPROP 0 LAST $SEC 1
J 0
(-3350 3000);
DISPLAY 0.680851 (-3350 3000);
PAINT MONO (-3350 3000);
DISPLAY INVISIBLE (-3350 3000);
FORCEPROP 0 LAST CDS_SEC 1
J 0
(-3350 3000);
DISPLAY 1.021277 (-3350 3000);
DISPLAY INVISIBLE (-3350 3000);
FORCEPROP 1 LASTPIN (-3100 2950) $PN 1
J 2
(-3112 2962);
DISPLAY 0.489362 (-3112 2962);
PAINT MONO (-3112 2962);
FORCEPROP 1 LASTPIN (-3300 2950) $PN 2
J 2
(-3262 2962);
DISPLAY 0.489362 (-3262 2962);
PAINT MONO (-3262 2962);
FORCEPROP 1 LAST VALUE 0
J 0
(-3100 2950);
DISPLAY 0.489362 (-3100 2950);
PAINT SKYBLUE (-3100 2950);
FORCEPROP 2 LAST CDS_LIB pure_quanta
J 0
(-3200 2950);
DISPLAY INVISIBLE (-3200 2950);
FORCEPROP 1 LAST PATH I35
J 2
(-3150 3100);
DISPLAY 0.978723 (-3150 3100);
PAINT WHITE (-3150 3100);
DISPLAY INVISIBLE (-3150 3100);
FORCEPROP 1 LAST WATTAGE 1/16W
J 0
(-3600 2875);
DISPLAY 0.489362 (-3600 2875);
PAINT SKYBLUE (-3600 2875);
DISPLAY INVISIBLE (-3600 2875);
FORCEPROP 1 LAST MATERIAL CHIP
J 2
(-3625 2875);
DISPLAY 0.489362 (-3625 2875);
PAINT SKYBLUE (-3625 2875);
DISPLAY INVISIBLE (-3625 2875);
FORCEPROP 1 LAST TOLERANCE 5%
J 2
(-3175 2875);
DISPLAY 0.489362 (-3175 2875);
PAINT SKYBLUE (-3175 2875);
DISPLAY INVISIBLE (-3175 2875);
FORCEPROP 1 LAST PART_NUMBER CS00002JB38
J 2
(-3225 3000);
DISPLAY 0.489362 (-3225 3000);
PAINT SKYBLUE (-3225 3000);
DISPLAY INVISIBLE (-3225 3000);
FORCEPROP 1 LAST PACK_TYPE 0402LF
J 2
(-3250 2875);
DISPLAY 0.489362 (-3250 2875);
PAINT SKYBLUE (-3250 2875);
DISPLAY INVISIBLE (-3250 2875);
FORCEADD Q_RES..1
R 2
(-3200 2900);
FORCEPROP 1 LAST LOCATION R1294
J 2
(-3350 2900);
DISPLAY 0.489362 (-3350 2900);
PAINT SKYBLUE (-3350 2900);
FORCEPROP 0 LAST $SEC 1
J 0
(-3350 2950);
DISPLAY 0.680851 (-3350 2950);
PAINT MONO (-3350 2950);
DISPLAY INVISIBLE (-3350 2950);
FORCEPROP 0 LAST CDS_SEC 1
J 0
(-3350 2950);
DISPLAY 1.021277 (-3350 2950);
DISPLAY INVISIBLE (-3350 2950);
FORCEPROP 1 LASTPIN (-3100 2900) $PN 1
J 2
(-3112 2912);
DISPLAY 0.489362 (-3112 2912);
PAINT MONO (-3112 2912);
FORCEPROP 1 LASTPIN (-3300 2900) $PN 2
J 2
(-3262 2912);
DISPLAY 0.489362 (-3262 2912);
PAINT MONO (-3262 2912);
FORCEPROP 1 LAST VALUE 0
J 0
(-3100 2900);
DISPLAY 0.489362 (-3100 2900);
PAINT SKYBLUE (-3100 2900);
FORCEPROP 2 LAST CDS_LIB pure_quanta
J 0
(-3200 2900);
DISPLAY INVISIBLE (-3200 2900);
FORCEPROP 1 LAST PATH I36
J 2
(-3150 3050);
DISPLAY 0.978723 (-3150 3050);
PAINT WHITE (-3150 3050);
DISPLAY INVISIBLE (-3150 3050);
FORCEPROP 1 LAST WATTAGE 1/16W
J 0
(-3600 2825);
DISPLAY 0.489362 (-3600 2825);
PAINT SKYBLUE (-3600 2825);
DISPLAY INVISIBLE (-3600 2825);
FORCEPROP 1 LAST MATERIAL CHIP
J 2
(-3625 2825);
DISPLAY 0.489362 (-3625 2825);
PAINT SKYBLUE (-3625 2825);
DISPLAY INVISIBLE (-3625 2825);
FORCEPROP 1 LAST TOLERANCE 5%
J 2
(-3175 2825);
DISPLAY 0.489362 (-3175 2825);
PAINT SKYBLUE (-3175 2825);
DISPLAY INVISIBLE (-3175 2825);
FORCEPROP 1 LAST PART_NUMBER CS00002JB38
J 2
(-3225 2950);
DISPLAY 0.489362 (-3225 2950);
PAINT SKYBLUE (-3225 2950);
DISPLAY INVISIBLE (-3225 2950);
FORCEPROP 1 LAST PACK_TYPE 0402LF
J 2
(-3250 2825);
DISPLAY 0.489362 (-3250 2825);
PAINT SKYBLUE (-3250 2825);
DISPLAY INVISIBLE (-3250 2825);
FORCEADD Q_RES..1
R 2
(-3175 1500);
FORCEPROP 1 LAST LOCATION R1295
J 2
(-3325 1500);
DISPLAY 0.489362 (-3325 1500);
PAINT SKYBLUE (-3325 1500);
FORCEPROP 0 LAST $SEC 1
J 0
(-3325 1550);
DISPLAY 0.680851 (-3325 1550);
PAINT MONO (-3325 1550);
DISPLAY INVISIBLE (-3325 1550);
FORCEPROP 0 LAST CDS_SEC 1
J 0
(-3325 1550);
DISPLAY 1.021277 (-3325 1550);
DISPLAY INVISIBLE (-3325 1550);
FORCEPROP 1 LASTPIN (-3075 1500) $PN 1
J 2
(-3087 1512);
DISPLAY 0.489362 (-3087 1512);
PAINT MONO (-3087 1512);
FORCEPROP 1 LASTPIN (-3275 1500) $PN 2
J 2
(-3237 1512);
DISPLAY 0.489362 (-3237 1512);
PAINT MONO (-3237 1512);
FORCEPROP 1 LAST VALUE 0
J 0
(-3075 1500);
DISPLAY 0.489362 (-3075 1500);
PAINT SKYBLUE (-3075 1500);
FORCEPROP 2 LAST CDS_LIB pure_quanta
J 0
(-3175 1500);
DISPLAY INVISIBLE (-3175 1500);
FORCEPROP 1 LAST PATH I37
J 2
(-3125 1650);
DISPLAY 0.978723 (-3125 1650);
PAINT WHITE (-3125 1650);
DISPLAY INVISIBLE (-3125 1650);
FORCEPROP 1 LAST WATTAGE 1/16W
J 0
(-3575 1425);
DISPLAY 0.489362 (-3575 1425);
PAINT SKYBLUE (-3575 1425);
DISPLAY INVISIBLE (-3575 1425);
FORCEPROP 1 LAST MATERIAL CHIP
J 2
(-3600 1425);
DISPLAY 0.489362 (-3600 1425);
PAINT SKYBLUE (-3600 1425);
DISPLAY INVISIBLE (-3600 1425);
FORCEPROP 1 LAST TOLERANCE 5%
J 2
(-3150 1425);
DISPLAY 0.489362 (-3150 1425);
PAINT SKYBLUE (-3150 1425);
DISPLAY INVISIBLE (-3150 1425);
FORCEPROP 1 LAST PART_NUMBER CS00002JB38
J 2
(-3200 1550);
DISPLAY 0.489362 (-3200 1550);
PAINT SKYBLUE (-3200 1550);
DISPLAY INVISIBLE (-3200 1550);
FORCEPROP 1 LAST PACK_TYPE 0402LF
J 2
(-3225 1425);
DISPLAY 0.489362 (-3225 1425);
PAINT SKYBLUE (-3225 1425);
DISPLAY INVISIBLE (-3225 1425);
FORCEADD Q_RES..1
R 2
(-3175 1450);
FORCEPROP 1 LAST LOCATION R1296
J 2
(-3325 1450);
DISPLAY 0.489362 (-3325 1450);
PAINT SKYBLUE (-3325 1450);
FORCEPROP 0 LAST $SEC 1
J 0
(-3325 1500);
DISPLAY 0.680851 (-3325 1500);
PAINT MONO (-3325 1500);
DISPLAY INVISIBLE (-3325 1500);
FORCEPROP 0 LAST CDS_SEC 1
J 0
(-3325 1500);
DISPLAY 1.021277 (-3325 1500);
DISPLAY INVISIBLE (-3325 1500);
FORCEPROP 1 LASTPIN (-3075 1450) $PN 1
J 2
(-3087 1462);
DISPLAY 0.489362 (-3087 1462);
PAINT MONO (-3087 1462);
FORCEPROP 1 LASTPIN (-3275 1450) $PN 2
J 2
(-3237 1462);
DISPLAY 0.489362 (-3237 1462);
PAINT MONO (-3237 1462);
FORCEPROP 1 LAST VALUE 0
J 0
(-3075 1450);
DISPLAY 0.489362 (-3075 1450);
PAINT SKYBLUE (-3075 1450);
FORCEPROP 2 LAST CDS_LIB pure_quanta
J 0
(-3175 1450);
DISPLAY INVISIBLE (-3175 1450);
FORCEPROP 1 LAST PATH I38
J 2
(-3125 1600);
DISPLAY 0.978723 (-3125 1600);
PAINT WHITE (-3125 1600);
DISPLAY INVISIBLE (-3125 1600);
FORCEPROP 1 LAST WATTAGE 1/16W
J 0
(-3575 1375);
DISPLAY 0.489362 (-3575 1375);
PAINT SKYBLUE (-3575 1375);
DISPLAY INVISIBLE (-3575 1375);
FORCEPROP 1 LAST MATERIAL CHIP
J 2
(-3600 1375);
DISPLAY 0.489362 (-3600 1375);
PAINT SKYBLUE (-3600 1375);
DISPLAY INVISIBLE (-3600 1375);
FORCEPROP 1 LAST TOLERANCE 5%
J 2
(-3150 1375);
DISPLAY 0.489362 (-3150 1375);
PAINT SKYBLUE (-3150 1375);
DISPLAY INVISIBLE (-3150 1375);
FORCEPROP 1 LAST PART_NUMBER CS00002JB38
J 2
(-3200 1500);
DISPLAY 0.489362 (-3200 1500);
PAINT SKYBLUE (-3200 1500);
DISPLAY INVISIBLE (-3200 1500);
FORCEPROP 1 LAST PACK_TYPE 0402LF
J 2
(-3225 1375);
DISPLAY 0.489362 (-3225 1375);
PAINT SKYBLUE (-3225 1375);
DISPLAY INVISIBLE (-3225 1375);
FORCEADD OFFPAGE..1
(-5975 5875);
FORCEPROP 2 LAST $XR0 79 
J 0
(-6196 5875);
DISPLAY 0.638298 (-6196 5875);
PAINT MONO (-6196 5875);
FORCEPROP 2 LAST PATH I39
J 0
(-5925 5950);
DISPLAY 1.021277 (-5925 5950);
DISPLAY INVISIBLE (-5925 5950);
FORCEPROP 1 LAST COMMENT_BODY TRUE
J 0
(-5850 5775);
DISPLAY 0.872340 (-5850 5775);
PAINT GREEN (-5850 5775);
DISPLAY INVISIBLE (-5850 5775);
FORCEPROP 1 LAST OFFPAGE TRUE
J 0
(-5650 5750);
DISPLAY 0.872340 (-5650 5750);
PAINT GREEN (-5650 5750);
DISPLAY INVISIBLE (-5650 5750);
FORCEPROP 2 LAST CDS_LIB standard
J 0
(-5975 5875);
DISPLAY INVISIBLE (-5975 5875);
FORCEADD OFFPAGE..1
(-5975 5925);
FORCEPROP 2 LAST $XR1 82 
J 0
(-6286 5925);
DISPLAY 0.638298 (-6286 5925);
PAINT MONO (-6286 5925);
FORCEPROP 2 LAST $XR0 79 
J 0
(-6196 5925);
DISPLAY 0.638298 (-6196 5925);
PAINT MONO (-6196 5925);
FORCEPROP 2 LAST PATH I40
J 0
(-5925 6000);
DISPLAY 1.021277 (-5925 6000);
DISPLAY INVISIBLE (-5925 6000);
FORCEPROP 1 LAST COMMENT_BODY TRUE
J 0
(-5850 5825);
DISPLAY 0.872340 (-5850 5825);
PAINT GREEN (-5850 5825);
DISPLAY INVISIBLE (-5850 5825);
FORCEPROP 1 LAST OFFPAGE TRUE
J 0
(-5650 5800);
DISPLAY 0.872340 (-5650 5800);
PAINT GREEN (-5650 5800);
DISPLAY INVISIBLE (-5650 5800);
FORCEPROP 2 LAST CDS_LIB standard
J 0
(-5975 5925);
DISPLAY INVISIBLE (-5975 5925);
FORCEADD OFFPAGE..1
(-5950 4525);
FORCEPROP 2 LAST $XR1 82 
J 0
(-6261 4525);
DISPLAY 0.638298 (-6261 4525);
PAINT MONO (-6261 4525);
FORCEPROP 2 LAST $XR0 79 
J 0
(-6171 4525);
DISPLAY 0.638298 (-6171 4525);
PAINT MONO (-6171 4525);
FORCEPROP 2 LAST PATH I41
J 0
(-5900 4600);
DISPLAY 1.021277 (-5900 4600);
DISPLAY INVISIBLE (-5900 4600);
FORCEPROP 1 LAST COMMENT_BODY TRUE
J 0
(-5825 4425);
DISPLAY 0.872340 (-5825 4425);
PAINT GREEN (-5825 4425);
DISPLAY INVISIBLE (-5825 4425);
FORCEPROP 1 LAST OFFPAGE TRUE
J 0
(-5625 4400);
DISPLAY 0.872340 (-5625 4400);
PAINT GREEN (-5625 4400);
DISPLAY INVISIBLE (-5625 4400);
FORCEPROP 2 LAST CDS_LIB standard
J 0
(-5950 4525);
DISPLAY INVISIBLE (-5950 4525);
FORCEADD OFFPAGE..1
(-5950 4475);
FORCEPROP 2 LAST $XR0 79 
J 0
(-6171 4475);
DISPLAY 0.638298 (-6171 4475);
PAINT MONO (-6171 4475);
FORCEPROP 2 LAST PATH I42
J 0
(-5900 4550);
DISPLAY 1.021277 (-5900 4550);
DISPLAY INVISIBLE (-5900 4550);
FORCEPROP 1 LAST COMMENT_BODY TRUE
J 0
(-5825 4375);
DISPLAY 0.872340 (-5825 4375);
PAINT GREEN (-5825 4375);
DISPLAY INVISIBLE (-5825 4375);
FORCEPROP 1 LAST OFFPAGE TRUE
J 0
(-5625 4350);
DISPLAY 0.872340 (-5625 4350);
PAINT GREEN (-5625 4350);
DISPLAY INVISIBLE (-5625 4350);
FORCEPROP 2 LAST CDS_LIB standard
J 0
(-5950 4475);
DISPLAY INVISIBLE (-5950 4475);
FORCEADD OFFPAGE..1
(-5950 2950);
FORCEPROP 2 LAST $XR0 79 
J 0
(-6171 2950);
DISPLAY 0.638298 (-6171 2950);
PAINT MONO (-6171 2950);
FORCEPROP 2 LAST PATH I43
J 0
(-5900 3025);
DISPLAY 1.021277 (-5900 3025);
DISPLAY INVISIBLE (-5900 3025);
FORCEPROP 1 LAST COMMENT_BODY TRUE
J 0
(-5825 2850);
DISPLAY 0.872340 (-5825 2850);
PAINT GREEN (-5825 2850);
DISPLAY INVISIBLE (-5825 2850);
FORCEPROP 1 LAST OFFPAGE TRUE
J 0
(-5625 2825);
DISPLAY 0.872340 (-5625 2825);
PAINT GREEN (-5625 2825);
DISPLAY INVISIBLE (-5625 2825);
FORCEPROP 2 LAST CDS_LIB standard
J 0
(-5950 2950);
DISPLAY INVISIBLE (-5950 2950);
FORCEADD OFFPAGE..1
(-5950 3000);
FORCEPROP 2 LAST $XR1 82 
J 0
(-6261 3000);
DISPLAY 0.638298 (-6261 3000);
PAINT MONO (-6261 3000);
FORCEPROP 2 LAST $XR0 79 
J 0
(-6171 3000);
DISPLAY 0.638298 (-6171 3000);
PAINT MONO (-6171 3000);
FORCEPROP 2 LAST PATH I44
J 0
(-5900 3075);
DISPLAY 1.021277 (-5900 3075);
DISPLAY INVISIBLE (-5900 3075);
FORCEPROP 1 LAST COMMENT_BODY TRUE
J 0
(-5825 2900);
DISPLAY 0.872340 (-5825 2900);
PAINT GREEN (-5825 2900);
DISPLAY INVISIBLE (-5825 2900);
FORCEPROP 1 LAST OFFPAGE TRUE
J 0
(-5625 2875);
DISPLAY 0.872340 (-5625 2875);
PAINT GREEN (-5625 2875);
DISPLAY INVISIBLE (-5625 2875);
FORCEPROP 2 LAST CDS_LIB standard
J 0
(-5950 3000);
DISPLAY INVISIBLE (-5950 3000);
FORCEADD OFFPAGE..1
(-5900 1550);
FORCEPROP 2 LAST $XR1 82 
J 0
(-6241 1550);
DISPLAY 0.638298 (-6241 1550);
PAINT MONO (-6241 1550);
FORCEPROP 2 LAST $XR0 79 
J 0
(-6151 1550);
DISPLAY 0.638298 (-6151 1550);
PAINT MONO (-6151 1550);
FORCEPROP 2 LAST PATH I45
J 0
(-5850 1625);
DISPLAY 1.021277 (-5850 1625);
DISPLAY INVISIBLE (-5850 1625);
FORCEPROP 1 LAST COMMENT_BODY TRUE
J 0
(-5775 1450);
DISPLAY 0.872340 (-5775 1450);
PAINT GREEN (-5775 1450);
DISPLAY INVISIBLE (-5775 1450);
FORCEPROP 1 LAST OFFPAGE TRUE
J 0
(-5575 1425);
DISPLAY 0.872340 (-5575 1425);
PAINT GREEN (-5575 1425);
DISPLAY INVISIBLE (-5575 1425);
FORCEPROP 2 LAST CDS_LIB standard
J 0
(-5900 1550);
DISPLAY INVISIBLE (-5900 1550);
FORCEADD OFFPAGE..1
(-5900 1500);
FORCEPROP 2 LAST $XR0 79 
J 0
(-6151 1500);
DISPLAY 0.638298 (-6151 1500);
PAINT MONO (-6151 1500);
FORCEPROP 2 LAST PATH I46
J 0
(-5850 1575);
DISPLAY 1.021277 (-5850 1575);
DISPLAY INVISIBLE (-5850 1575);
FORCEPROP 1 LAST COMMENT_BODY TRUE
J 0
(-5775 1400);
DISPLAY 0.872340 (-5775 1400);
PAINT GREEN (-5775 1400);
DISPLAY INVISIBLE (-5775 1400);
FORCEPROP 1 LAST OFFPAGE TRUE
J 0
(-5575 1375);
DISPLAY 0.872340 (-5575 1375);
PAINT GREEN (-5575 1375);
DISPLAY INVISIBLE (-5575 1375);
FORCEPROP 2 LAST CDS_LIB standard
J 0
(-5900 1500);
DISPLAY INVISIBLE (-5900 1500);
FORCEADD PI3CSW12ZUAEX..1
(-4775 5775);
FORCEPROP 1 LAST LOCATION U105
J 0
(-4919 6268);
DISPLAY 0.489362 (-4919 6268);
PAINT SKYBLUE (-4919 6268);
FORCEPROP 0 LAST $SEC 1
J 0
(-4900 6425);
DISPLAY 0.680851 (-4900 6425);
PAINT MONO (-4900 6425);
DISPLAY INVISIBLE (-4900 6425);
FORCEPROP 0 LAST CDS_SEC 1
J 0
(-4900 6425);
DISPLAY 1.021277 (-4900 6425);
DISPLAY INVISIBLE (-4900 6425);
FORCEPROP 0 LASTPIN (-5075 5775) $PN 1
J 2
(-5085 5785);
DISPLAY 0.489362 (-5085 5785);
PAINT MONO (-5085 5785);
FORCEPROP 0 LASTPIN (-5075 5725) $PN 2
J 2
(-5085 5735);
DISPLAY 0.489362 (-5085 5735);
PAINT MONO (-5085 5735);
FORCEPROP 0 LASTPIN (-5075 5675) $PN 3
J 2
(-5085 5685);
DISPLAY 0.489362 (-5085 5685);
PAINT MONO (-5085 5685);
FORCEPROP 0 LASTPIN (-5075 5625) $PN 4
J 2
(-5085 5635);
DISPLAY 0.489362 (-5085 5635);
PAINT MONO (-5085 5635);
FORCEPROP 0 LASTPIN (-4475 5875) $PN 8
J 0
(-4465 5885);
DISPLAY 0.489362 (-4465 5885);
PAINT MONO (-4465 5885);
FORCEPROP 0 LASTPIN (-4475 5825) $PN 7
J 0
(-4465 5835);
DISPLAY 0.489362 (-4465 5835);
PAINT MONO (-4465 5835);
FORCEPROP 0 LASTPIN (-4475 5625) $PN 5
J 0
(-4465 5635);
DISPLAY 0.489362 (-4465 5635);
PAINT MONO (-4465 5635);
FORCEPROP 0 LASTPIN (-5075 5925) $PN 6
J 2
(-5085 5935);
DISPLAY 0.489362 (-5085 5935);
PAINT MONO (-5085 5935);
FORCEPROP 0 LASTPIN (-5075 5875) $PN 9
J 2
(-5085 5885);
DISPLAY 0.489362 (-5085 5885);
PAINT MONO (-5085 5885);
FORCEPROP 0 LASTPIN (-4475 5925) $PN 10
J 0
(-4465 5935);
DISPLAY 0.489362 (-4465 5935);
PAINT MONO (-4465 5935);
FORCEPROP 1 LAST MATERIAL IC
J 0
(-4919 5994);
DISPLAY 0.489362 (-4919 5994);
PAINT SKYBLUE (-4919 5994);
FORCEPROP 2 LAST PART_TYPE SMLF
J 0
(-4900 6375);
DISPLAY 1.021277 (-4900 6375);
FORCEPROP 2 LAST VALUE PI3CSW12ZUAEX
J 0
(-4900 6325);
DISPLAY 0.489362 (-4900 6325);
PAINT SKYBLUE (-4900 6325);
FORCEPROP 1 LAST PART_NUMBER AL3CSW12000
J 0
(-4919 6121);
DISPLAY 0.489362 (-4919 6121);
PAINT SKYBLUE (-4919 6121);
FORCEPROP 2 LAST CDS_LIB pure_quanta
J 0
(-4775 5775);
DISPLAY INVISIBLE (-4775 5775);
FORCEPROP 1 LAST CDS_LMAN_SYM_OUTLINE -150,200,150,-200
J 0
(-4775 5775);
DISPLAY 0.468085 (-4775 5775);
PAINT GREEN (-4775 5775);
DISPLAY INVISIBLE (-4775 5775);
FORCEPROP 1 LAST NEEDS_NO_SIZE TRUE
J 0
(-4775 5775);
DISPLAY 0.723404 (-4775 5775);
PAINT GREEN (-4775 5775);
DISPLAY INVISIBLE (-4775 5775);
FORCEPROP 1 LAST PATH I47
J 0
(-4775 5775);
DISPLAY 0.723404 (-4775 5775);
PAINT GREEN (-4775 5775);
DISPLAY INVISIBLE (-4775 5775);
FORCEADD UNIVERSAL_GND..1
(-4325 5450);
FORCEPROP 3 LASTPIN (-4325 5500) SIG_NAME GND\g
J 0
(-4315 5510);
DISPLAY 0.659574 (-4315 5510);
PAINT MONO (-4315 5510);
DISPLAY INVISIBLE (-4315 5510);
FORCEPROP 2 LAST CDS_LIB pure_quanta_power
J 0
(-4325 5450);
DISPLAY INVISIBLE (-4325 5450);
FORCEPROP 1 LAST PATH I48
J 0
(-4250 5450);
DISPLAY 0.872340 (-4250 5450);
PAINT AQUA (-4250 5450);
DISPLAY INVISIBLE (-4250 5450);
FORCEPROP 1 LAST HDL_POWER GND
J 1
(-4300 5375);
DISPLAY 0.872340 (-4300 5375);
PAINT GREEN (-4300 5375);
DISPLAY INVISIBLE (-4300 5375);
FORCEADD UNIVERSAL_GND..1
(-4275 6000);
FORCEPROP 3 LASTPIN (-4275 6050) SIG_NAME GND\g
J 0
(-4265 6060);
DISPLAY 0.659574 (-4265 6060);
PAINT MONO (-4265 6060);
DISPLAY INVISIBLE (-4265 6060);
FORCEPROP 2 LAST CDS_LIB pure_quanta_power
J 2
(-4275 6000);
DISPLAY INVISIBLE (-4275 6000);
FORCEPROP 1 LAST PATH I49
J 0
(-4200 6000);
DISPLAY 0.872340 (-4200 6000);
PAINT AQUA (-4200 6000);
DISPLAY INVISIBLE (-4200 6000);
FORCEPROP 1 LAST HDL_POWER GND
J 1
(-4250 5925);
DISPLAY 0.872340 (-4250 5925);
PAINT GREEN (-4250 5925);
DISPLAY INVISIBLE (-4250 5925);
FORCEADD Q_CAP..1
(-4275 6200);
FORCEPROP 1 LAST LOCATION C1336
J 0
(-4225 6350);
DISPLAY 0.489362 (-4225 6350);
PAINT SKYBLUE (-4225 6350);
FORCEPROP 0 LAST $SEC 1
J 2
(-4225 6375);
DISPLAY 0.680851 (-4225 6375);
PAINT MONO (-4225 6375);
DISPLAY INVISIBLE (-4225 6375);
FORCEPROP 0 LAST CDS_SEC 1
J 2
(-4225 6375);
DISPLAY 1.021277 (-4225 6375);
DISPLAY INVISIBLE (-4225 6375);
FORCEPROP 1 LASTPIN (-4275 6300) $PN 1
J 0
(-4265 6280);
DISPLAY 0.489362 (-4265 6280);
PAINT MONO (-4265 6280);
FORCEPROP 1 LASTPIN (-4275 6100) $PN 2
J 0
(-4265 6080);
DISPLAY 0.489362 (-4265 6080);
PAINT MONO (-4265 6080);
FORCEPROP 1 LAST PART_NUMBER CH4104K1B00
J 0
(-4225 6050);
DISPLAY 0.489362 (-4225 6050);
PAINT SKYBLUE (-4225 6050);
FORCEPROP 1 LAST PACK_TYPE 0402
J 0
(-4225 6100);
DISPLAY 0.489362 (-4225 6100);
PAINT SKYBLUE (-4225 6100);
FORCEPROP 1 LAST TOLERANCE 10%
J 0
(-4225 6200);
DISPLAY 0.489362 (-4225 6200);
PAINT SKYBLUE (-4225 6200);
FORCEPROP 1 LAST VOLTAGE 25V
J 0
(-4225 6250);
DISPLAY 0.489362 (-4225 6250);
PAINT SKYBLUE (-4225 6250);
FORCEPROP 1 LAST MATERIAL X7R
J 0
(-4225 6150);
DISPLAY 0.489362 (-4225 6150);
PAINT SKYBLUE (-4225 6150);
FORCEPROP 1 LAST VALUE 0.1UF
J 0
(-4225 6300);
DISPLAY 0.489362 (-4225 6300);
PAINT SKYBLUE (-4225 6300);
FORCEPROP 2 LAST CDS_LIB pure_quanta
J 2
(-4275 6200);
DISPLAY INVISIBLE (-4275 6200);
FORCEPROP 1 LAST PATH I50
J 0
(-4225 6350);
DISPLAY 0.978723 (-4225 6350);
PAINT WHITE (-4225 6350);
DISPLAY INVISIBLE (-4225 6350);
FORCEADD UNIVERSAL_POWER..1
R 2
(-4350 6475);
FORCEPROP 3 LASTPIN (-4350 6425) SIG_NAME P3V3_STBY\g
J 0
(-4340 6435);
DISPLAY 0.659574 (-4340 6435);
PAINT MONO (-4340 6435);
DISPLAY INVISIBLE (-4340 6435);
FORCEPROP 1 LAST HDL_POWER P3V3_STBY
J 1
(-4350 6525);
DISPLAY 0.489362 (-4350 6525);
PAINT GREEN (-4350 6525);
FORCEPROP 2 LAST CDS_LIB pure_quanta_power
J 2
(-4350 6475);
DISPLAY INVISIBLE (-4350 6475);
FORCEPROP 1 LAST PATH I51
J 2
(-4400 6500);
DISPLAY 0.872340 (-4400 6500);
PAINT AQUA (-4400 6500);
DISPLAY INVISIBLE (-4400 6500);
FORCEADD OFFPAGE..3
(-1825 5825);
FORCEPROP 2 LAST $XR5 90 
J 0
(-1161 5825);
DISPLAY 0.638298 (-1161 5825);
PAINT MONO (-1161 5825);
FORCEPROP 2 LAST $XR4 89 
J 0
(-1251 5825);
DISPLAY 0.638298 (-1251 5825);
PAINT MONO (-1251 5825);
FORCEPROP 2 LAST $XR3 88 
J 0
(-1341 5825);
DISPLAY 0.638298 (-1341 5825);
PAINT MONO (-1341 5825);
FORCEPROP 2 LAST $XR2 87 
J 0
(-1431 5825);
DISPLAY 0.638298 (-1431 5825);
PAINT MONO (-1431 5825);
FORCEPROP 2 LAST $XR1 86 
J 0
(-1521 5825);
DISPLAY 0.638298 (-1521 5825);
PAINT MONO (-1521 5825);
FORCEPROP 2 LAST $XR0 85 
J 0
(-1611 5825);
DISPLAY 0.638298 (-1611 5825);
PAINT MONO (-1611 5825);
FORCEPROP 2 LAST CDS_LIB standard
J 0
(-1825 5825);
DISPLAY INVISIBLE (-1825 5825);
FORCEPROP 1 LAST OFFPAGE TRUE
J 0
(-1500 5700);
DISPLAY 0.872340 (-1500 5700);
PAINT GREEN (-1500 5700);
DISPLAY INVISIBLE (-1500 5700);
FORCEPROP 1 LAST COMMENT_BODY TRUE
J 0
(-1875 5725);
DISPLAY 0.872340 (-1875 5725);
PAINT GREEN (-1875 5725);
DISPLAY INVISIBLE (-1875 5725);
FORCEPROP 2 LAST PATH I52
J 0
(-1600 5875);
DISPLAY 1.021277 (-1600 5875);
DISPLAY INVISIBLE (-1600 5875);
FORCEADD OFFPAGE..2
(-1825 5875);
FORCEPROP 2 LAST $XR5 90 
J 0
(-1186 5875);
DISPLAY 0.638298 (-1186 5875);
PAINT MONO (-1186 5875);
FORCEPROP 2 LAST $XR4 89 
J 0
(-1276 5875);
DISPLAY 0.638298 (-1276 5875);
PAINT MONO (-1276 5875);
FORCEPROP 2 LAST $XR3 88 
J 0
(-1366 5875);
DISPLAY 0.638298 (-1366 5875);
PAINT MONO (-1366 5875);
FORCEPROP 2 LAST $XR2 87 
J 0
(-1456 5875);
DISPLAY 0.638298 (-1456 5875);
PAINT MONO (-1456 5875);
FORCEPROP 2 LAST $XR1 86 
J 0
(-1546 5875);
DISPLAY 0.638298 (-1546 5875);
PAINT MONO (-1546 5875);
FORCEPROP 2 LAST $XR0 85 
J 0
(-1636 5875);
DISPLAY 0.638298 (-1636 5875);
PAINT MONO (-1636 5875);
FORCEPROP 2 LAST CDS_LIB standard
J 0
(-1825 5875);
DISPLAY INVISIBLE (-1825 5875);
FORCEPROP 1 LAST OFFPAGE TRUE
J 0
(-1500 5750);
DISPLAY 0.872340 (-1500 5750);
PAINT GREEN (-1500 5750);
DISPLAY INVISIBLE (-1500 5750);
FORCEPROP 1 LAST COMMENT_BODY TRUE
J 0
(-1870 5780);
DISPLAY 0.872340 (-1870 5780);
PAINT GREEN (-1870 5780);
DISPLAY INVISIBLE (-1870 5780);
FORCEPROP 2 LAST PATH I53
J 0
(-1625 5925);
DISPLAY 1.021277 (-1625 5925);
DISPLAY INVISIBLE (-1625 5925);
FORCEADD PI3CSW12ZUAEX..1
(-4750 4375);
FORCEPROP 1 LAST LOCATION U106
J 0
(-4894 4868);
DISPLAY 0.489362 (-4894 4868);
PAINT SKYBLUE (-4894 4868);
FORCEPROP 0 LAST $SEC 1
J 0
(-4875 5025);
DISPLAY 0.680851 (-4875 5025);
PAINT MONO (-4875 5025);
DISPLAY INVISIBLE (-4875 5025);
FORCEPROP 0 LAST CDS_SEC 1
J 0
(-4875 5025);
DISPLAY 1.021277 (-4875 5025);
DISPLAY INVISIBLE (-4875 5025);
FORCEPROP 0 LASTPIN (-5050 4375) $PN 1
J 2
(-5060 4385);
DISPLAY 0.489362 (-5060 4385);
PAINT MONO (-5060 4385);
FORCEPROP 0 LASTPIN (-5050 4325) $PN 2
J 2
(-5060 4335);
DISPLAY 0.489362 (-5060 4335);
PAINT MONO (-5060 4335);
FORCEPROP 0 LASTPIN (-5050 4275) $PN 3
J 2
(-5060 4285);
DISPLAY 0.489362 (-5060 4285);
PAINT MONO (-5060 4285);
FORCEPROP 0 LASTPIN (-5050 4225) $PN 4
J 2
(-5060 4235);
DISPLAY 0.489362 (-5060 4235);
PAINT MONO (-5060 4235);
FORCEPROP 0 LASTPIN (-4450 4475) $PN 8
J 0
(-4440 4485);
DISPLAY 0.489362 (-4440 4485);
PAINT MONO (-4440 4485);
FORCEPROP 0 LASTPIN (-4450 4425) $PN 7
J 0
(-4440 4435);
DISPLAY 0.489362 (-4440 4435);
PAINT MONO (-4440 4435);
FORCEPROP 0 LASTPIN (-4450 4225) $PN 5
J 0
(-4440 4235);
DISPLAY 0.489362 (-4440 4235);
PAINT MONO (-4440 4235);
FORCEPROP 0 LASTPIN (-5050 4525) $PN 6
J 2
(-5060 4535);
DISPLAY 0.489362 (-5060 4535);
PAINT MONO (-5060 4535);
FORCEPROP 0 LASTPIN (-5050 4475) $PN 9
J 2
(-5060 4485);
DISPLAY 0.489362 (-5060 4485);
PAINT MONO (-5060 4485);
FORCEPROP 0 LASTPIN (-4450 4525) $PN 10
J 0
(-4440 4535);
DISPLAY 0.489362 (-4440 4535);
PAINT MONO (-4440 4535);
FORCEPROP 2 LAST VALUE PI3CSW12ZUAEX
J 0
(-4875 4925);
DISPLAY 0.489362 (-4875 4925);
PAINT SKYBLUE (-4875 4925);
FORCEPROP 2 LAST PART_TYPE SMLF
J 0
(-4875 4975);
DISPLAY 1.021277 (-4875 4975);
FORCEPROP 1 LAST MATERIAL IC
J 0
(-4894 4594);
DISPLAY 0.489362 (-4894 4594);
PAINT SKYBLUE (-4894 4594);
FORCEPROP 1 LAST PART_NUMBER AL3CSW12000
J 0
(-4894 4721);
DISPLAY 0.489362 (-4894 4721);
PAINT SKYBLUE (-4894 4721);
FORCEPROP 2 LAST CDS_LIB pure_quanta
J 0
(-4750 4375);
DISPLAY INVISIBLE (-4750 4375);
FORCEPROP 1 LAST CDS_LMAN_SYM_OUTLINE -150,200,150,-200
J 0
(-4750 4375);
DISPLAY 0.468085 (-4750 4375);
PAINT GREEN (-4750 4375);
DISPLAY INVISIBLE (-4750 4375);
FORCEPROP 1 LAST NEEDS_NO_SIZE TRUE
J 0
(-4750 4375);
DISPLAY 0.723404 (-4750 4375);
PAINT GREEN (-4750 4375);
DISPLAY INVISIBLE (-4750 4375);
FORCEPROP 1 LAST PATH I54
J 0
(-4750 4375);
DISPLAY 0.723404 (-4750 4375);
PAINT GREEN (-4750 4375);
DISPLAY INVISIBLE (-4750 4375);
FORCEADD UNIVERSAL_POWER..1
R 2
(-4325 5075);
FORCEPROP 3 LASTPIN (-4325 5025) SIG_NAME P3V3_STBY\g
J 0
(-4315 5035);
DISPLAY 0.659574 (-4315 5035);
PAINT MONO (-4315 5035);
DISPLAY INVISIBLE (-4315 5035);
FORCEPROP 1 LAST HDL_POWER P3V3_STBY
J 1
(-4325 5125);
DISPLAY 0.489362 (-4325 5125);
PAINT GREEN (-4325 5125);
FORCEPROP 2 LAST CDS_LIB pure_quanta_power
J 2
(-4325 5075);
DISPLAY INVISIBLE (-4325 5075);
FORCEPROP 1 LAST PATH I55
J 2
(-4375 5100);
DISPLAY 0.872340 (-4375 5100);
PAINT AQUA (-4375 5100);
DISPLAY INVISIBLE (-4375 5100);
FORCEADD Q_CAP..1
(-4250 4800);
FORCEPROP 1 LAST LOCATION C1337
J 0
(-4200 4950);
DISPLAY 0.489362 (-4200 4950);
PAINT SKYBLUE (-4200 4950);
FORCEPROP 0 LAST $SEC 1
J 2
(-4200 4975);
DISPLAY 0.680851 (-4200 4975);
PAINT MONO (-4200 4975);
DISPLAY INVISIBLE (-4200 4975);
FORCEPROP 0 LAST CDS_SEC 1
J 2
(-4200 4975);
DISPLAY 1.021277 (-4200 4975);
DISPLAY INVISIBLE (-4200 4975);
FORCEPROP 1 LASTPIN (-4250 4900) $PN 1
J 0
(-4240 4880);
DISPLAY 0.489362 (-4240 4880);
PAINT MONO (-4240 4880);
FORCEPROP 1 LASTPIN (-4250 4700) $PN 2
J 0
(-4240 4680);
DISPLAY 0.489362 (-4240 4680);
PAINT MONO (-4240 4680);
FORCEPROP 1 LAST MATERIAL X7R
J 0
(-4200 4750);
DISPLAY 0.489362 (-4200 4750);
PAINT SKYBLUE (-4200 4750);
FORCEPROP 1 LAST TOLERANCE 10%
J 0
(-4200 4800);
DISPLAY 0.489362 (-4200 4800);
PAINT SKYBLUE (-4200 4800);
FORCEPROP 1 LAST VOLTAGE 25V
J 0
(-4200 4850);
DISPLAY 0.489362 (-4200 4850);
PAINT SKYBLUE (-4200 4850);
FORCEPROP 1 LAST PART_NUMBER CH4104K1B00
J 0
(-4200 4650);
DISPLAY 0.489362 (-4200 4650);
PAINT SKYBLUE (-4200 4650);
FORCEPROP 1 LAST VALUE 0.1UF
J 0
(-4200 4900);
DISPLAY 0.489362 (-4200 4900);
PAINT SKYBLUE (-4200 4900);
FORCEPROP 1 LAST PACK_TYPE 0402
J 0
(-4200 4700);
DISPLAY 0.489362 (-4200 4700);
PAINT SKYBLUE (-4200 4700);
FORCEPROP 2 LAST CDS_LIB pure_quanta
J 2
(-4250 4800);
DISPLAY INVISIBLE (-4250 4800);
FORCEPROP 1 LAST PATH I56
J 0
(-4200 4950);
DISPLAY 0.978723 (-4200 4950);
PAINT WHITE (-4200 4950);
DISPLAY INVISIBLE (-4200 4950);
FORCEADD UNIVERSAL_GND..1
(-4250 4600);
FORCEPROP 3 LASTPIN (-4250 4650) SIG_NAME GND\g
J 0
(-4240 4660);
DISPLAY 0.659574 (-4240 4660);
PAINT MONO (-4240 4660);
DISPLAY INVISIBLE (-4240 4660);
FORCEPROP 2 LAST CDS_LIB pure_quanta_power
J 2
(-4250 4600);
DISPLAY INVISIBLE (-4250 4600);
FORCEPROP 1 LAST PATH I57
J 0
(-4175 4600);
DISPLAY 0.872340 (-4175 4600);
PAINT AQUA (-4175 4600);
DISPLAY INVISIBLE (-4175 4600);
FORCEPROP 1 LAST HDL_POWER GND
J 1
(-4225 4525);
DISPLAY 0.872340 (-4225 4525);
PAINT GREEN (-4225 4525);
DISPLAY INVISIBLE (-4225 4525);
FORCEADD UNIVERSAL_GND..1
(-4300 4050);
FORCEPROP 3 LASTPIN (-4300 4100) SIG_NAME GND\g
J 0
(-4290 4110);
DISPLAY 0.659574 (-4290 4110);
PAINT MONO (-4290 4110);
DISPLAY INVISIBLE (-4290 4110);
FORCEPROP 2 LAST CDS_LIB pure_quanta_power
J 0
(-4300 4050);
DISPLAY INVISIBLE (-4300 4050);
FORCEPROP 1 LAST PATH I58
J 0
(-4225 4050);
DISPLAY 0.872340 (-4225 4050);
PAINT AQUA (-4225 4050);
DISPLAY INVISIBLE (-4225 4050);
FORCEPROP 1 LAST HDL_POWER GND
J 1
(-4275 3975);
DISPLAY 0.872340 (-4275 3975);
PAINT GREEN (-4275 3975);
DISPLAY INVISIBLE (-4275 3975);
FORCEADD UNIVERSAL_GND..1
(-4300 2525);
FORCEPROP 3 LASTPIN (-4300 2575) SIG_NAME GND\g
J 0
(-4290 2585);
DISPLAY 0.659574 (-4290 2585);
PAINT MONO (-4290 2585);
DISPLAY INVISIBLE (-4290 2585);
FORCEPROP 2 LAST CDS_LIB pure_quanta_power
J 0
(-4300 2525);
DISPLAY INVISIBLE (-4300 2525);
FORCEPROP 1 LAST PATH I59
J 0
(-4225 2525);
DISPLAY 0.872340 (-4225 2525);
PAINT AQUA (-4225 2525);
DISPLAY INVISIBLE (-4225 2525);
FORCEPROP 1 LAST HDL_POWER GND
J 1
(-4275 2450);
DISPLAY 0.872340 (-4275 2450);
PAINT GREEN (-4275 2450);
DISPLAY INVISIBLE (-4275 2450);
FORCEADD UNIVERSAL_GND..1
(-4250 3075);
FORCEPROP 3 LASTPIN (-4250 3125) SIG_NAME GND\g
J 0
(-4240 3135);
DISPLAY 0.659574 (-4240 3135);
PAINT MONO (-4240 3135);
DISPLAY INVISIBLE (-4240 3135);
FORCEPROP 2 LAST CDS_LIB pure_quanta_power
J 2
(-4250 3075);
DISPLAY INVISIBLE (-4250 3075);
FORCEPROP 1 LAST PATH I60
J 0
(-4175 3075);
DISPLAY 0.872340 (-4175 3075);
PAINT AQUA (-4175 3075);
DISPLAY INVISIBLE (-4175 3075);
FORCEPROP 1 LAST HDL_POWER GND
J 1
(-4225 3000);
DISPLAY 0.872340 (-4225 3000);
PAINT GREEN (-4225 3000);
DISPLAY INVISIBLE (-4225 3000);
FORCEADD Q_CAP..1
(-4250 3275);
FORCEPROP 1 LAST LOCATION C1338
J 0
(-4200 3425);
DISPLAY 0.489362 (-4200 3425);
PAINT SKYBLUE (-4200 3425);
FORCEPROP 0 LAST $SEC 1
J 2
(-4200 3450);
DISPLAY 0.680851 (-4200 3450);
PAINT MONO (-4200 3450);
DISPLAY INVISIBLE (-4200 3450);
FORCEPROP 0 LAST CDS_SEC 1
J 2
(-4200 3450);
DISPLAY 1.021277 (-4200 3450);
DISPLAY INVISIBLE (-4200 3450);
FORCEPROP 1 LASTPIN (-4250 3375) $PN 1
J 0
(-4240 3355);
DISPLAY 0.489362 (-4240 3355);
PAINT MONO (-4240 3355);
FORCEPROP 1 LASTPIN (-4250 3175) $PN 2
J 0
(-4240 3155);
DISPLAY 0.489362 (-4240 3155);
PAINT MONO (-4240 3155);
FORCEPROP 1 LAST VALUE 0.1UF
J 0
(-4200 3375);
DISPLAY 0.489362 (-4200 3375);
PAINT SKYBLUE (-4200 3375);
FORCEPROP 1 LAST TOLERANCE 10%
J 0
(-4200 3275);
DISPLAY 0.489362 (-4200 3275);
PAINT SKYBLUE (-4200 3275);
FORCEPROP 1 LAST MATERIAL X7R
J 0
(-4200 3225);
DISPLAY 0.489362 (-4200 3225);
PAINT SKYBLUE (-4200 3225);
FORCEPROP 1 LAST VOLTAGE 25V
J 0
(-4200 3325);
DISPLAY 0.489362 (-4200 3325);
PAINT SKYBLUE (-4200 3325);
FORCEPROP 1 LAST PACK_TYPE 0402
J 0
(-4200 3175);
DISPLAY 0.489362 (-4200 3175);
PAINT SKYBLUE (-4200 3175);
FORCEPROP 1 LAST PART_NUMBER CH4104K1B00
J 0
(-4200 3125);
DISPLAY 0.489362 (-4200 3125);
PAINT SKYBLUE (-4200 3125);
FORCEPROP 2 LAST CDS_LIB pure_quanta
J 2
(-4250 3275);
DISPLAY INVISIBLE (-4250 3275);
FORCEPROP 1 LAST PATH I61
J 0
(-4200 3425);
DISPLAY 0.978723 (-4200 3425);
PAINT WHITE (-4200 3425);
DISPLAY INVISIBLE (-4200 3425);
FORCEADD UNIVERSAL_POWER..1
R 2
(-4325 3550);
FORCEPROP 3 LASTPIN (-4325 3500) SIG_NAME P3V3_STBY\g
J 0
(-4315 3510);
DISPLAY 0.659574 (-4315 3510);
PAINT MONO (-4315 3510);
DISPLAY INVISIBLE (-4315 3510);
FORCEPROP 1 LAST HDL_POWER P3V3_STBY
J 1
(-4325 3600);
DISPLAY 0.489362 (-4325 3600);
PAINT GREEN (-4325 3600);
FORCEPROP 2 LAST CDS_LIB pure_quanta_power
J 2
(-4325 3550);
DISPLAY INVISIBLE (-4325 3550);
FORCEPROP 1 LAST PATH I62
J 2
(-4375 3575);
DISPLAY 0.872340 (-4375 3575);
PAINT AQUA (-4375 3575);
DISPLAY INVISIBLE (-4375 3575);
FORCEADD PI3CSW12ZUAEX..1
(-4750 2850);
FORCEPROP 1 LAST LOCATION U107
J 0
(-4894 3343);
DISPLAY 0.489362 (-4894 3343);
PAINT SKYBLUE (-4894 3343);
FORCEPROP 0 LAST $SEC 1
J 0
(-4875 3500);
DISPLAY 0.680851 (-4875 3500);
PAINT MONO (-4875 3500);
DISPLAY INVISIBLE (-4875 3500);
FORCEPROP 0 LAST CDS_SEC 1
J 0
(-4875 3500);
DISPLAY 1.021277 (-4875 3500);
DISPLAY INVISIBLE (-4875 3500);
FORCEPROP 0 LASTPIN (-5050 2850) $PN 1
J 2
(-5060 2860);
DISPLAY 0.489362 (-5060 2860);
PAINT MONO (-5060 2860);
FORCEPROP 0 LASTPIN (-5050 2800) $PN 2
J 2
(-5060 2810);
DISPLAY 0.489362 (-5060 2810);
PAINT MONO (-5060 2810);
FORCEPROP 0 LASTPIN (-5050 2750) $PN 3
J 2
(-5060 2760);
DISPLAY 0.489362 (-5060 2760);
PAINT MONO (-5060 2760);
FORCEPROP 0 LASTPIN (-5050 2700) $PN 4
J 2
(-5060 2710);
DISPLAY 0.489362 (-5060 2710);
PAINT MONO (-5060 2710);
FORCEPROP 0 LASTPIN (-4450 2950) $PN 8
J 0
(-4440 2960);
DISPLAY 0.489362 (-4440 2960);
PAINT MONO (-4440 2960);
FORCEPROP 0 LASTPIN (-4450 2900) $PN 7
J 0
(-4440 2910);
DISPLAY 0.489362 (-4440 2910);
PAINT MONO (-4440 2910);
FORCEPROP 0 LASTPIN (-4450 2700) $PN 5
J 0
(-4440 2710);
DISPLAY 0.489362 (-4440 2710);
PAINT MONO (-4440 2710);
FORCEPROP 0 LASTPIN (-5050 3000) $PN 6
J 2
(-5060 3010);
DISPLAY 0.489362 (-5060 3010);
PAINT MONO (-5060 3010);
FORCEPROP 0 LASTPIN (-5050 2950) $PN 9
J 2
(-5060 2960);
DISPLAY 0.489362 (-5060 2960);
PAINT MONO (-5060 2960);
FORCEPROP 0 LASTPIN (-4450 3000) $PN 10
J 0
(-4440 3010);
DISPLAY 0.489362 (-4440 3010);
PAINT MONO (-4440 3010);
FORCEPROP 2 LAST PART_TYPE SMLF
J 0
(-4875 3450);
DISPLAY 1.021277 (-4875 3450);
FORCEPROP 1 LAST MATERIAL IC
J 0
(-4894 3069);
DISPLAY 0.489362 (-4894 3069);
PAINT SKYBLUE (-4894 3069);
FORCEPROP 2 LAST VALUE PI3CSW12ZUAEX
J 0
(-4875 3400);
DISPLAY 0.489362 (-4875 3400);
PAINT SKYBLUE (-4875 3400);
FORCEPROP 1 LAST PART_NUMBER AL3CSW12000
J 0
(-4894 3196);
DISPLAY 0.489362 (-4894 3196);
PAINT SKYBLUE (-4894 3196);
FORCEPROP 2 LAST CDS_LIB pure_quanta
J 0
(-4750 2850);
DISPLAY INVISIBLE (-4750 2850);
FORCEPROP 1 LAST CDS_LMAN_SYM_OUTLINE -150,200,150,-200
J 0
(-4750 2850);
DISPLAY 0.468085 (-4750 2850);
PAINT GREEN (-4750 2850);
DISPLAY INVISIBLE (-4750 2850);
FORCEPROP 1 LAST NEEDS_NO_SIZE TRUE
J 0
(-4750 2850);
DISPLAY 0.723404 (-4750 2850);
PAINT GREEN (-4750 2850);
DISPLAY INVISIBLE (-4750 2850);
FORCEPROP 1 LAST PATH I63
J 0
(-4750 2850);
DISPLAY 0.723404 (-4750 2850);
PAINT GREEN (-4750 2850);
DISPLAY INVISIBLE (-4750 2850);
FORCEADD UNIVERSAL_GND..1
(-4250 1075);
FORCEPROP 3 LASTPIN (-4250 1125) SIG_NAME GND\g
J 0
(-4240 1135);
DISPLAY 0.659574 (-4240 1135);
PAINT MONO (-4240 1135);
DISPLAY INVISIBLE (-4240 1135);
FORCEPROP 2 LAST CDS_LIB pure_quanta_power
J 0
(-4250 1075);
DISPLAY INVISIBLE (-4250 1075);
FORCEPROP 1 LAST PATH I64
J 0
(-4175 1075);
DISPLAY 0.872340 (-4175 1075);
PAINT AQUA (-4175 1075);
DISPLAY INVISIBLE (-4175 1075);
FORCEPROP 1 LAST HDL_POWER GND
J 1
(-4225 1000);
DISPLAY 0.872340 (-4225 1000);
PAINT GREEN (-4225 1000);
DISPLAY INVISIBLE (-4225 1000);
FORCEADD UNIVERSAL_GND..1
(-4200 1625);
FORCEPROP 3 LASTPIN (-4200 1675) SIG_NAME GND\g
J 0
(-4190 1685);
DISPLAY 0.659574 (-4190 1685);
PAINT MONO (-4190 1685);
DISPLAY INVISIBLE (-4190 1685);
FORCEPROP 2 LAST CDS_LIB pure_quanta_power
J 2
(-4200 1625);
DISPLAY INVISIBLE (-4200 1625);
FORCEPROP 1 LAST PATH I65
J 0
(-4125 1625);
DISPLAY 0.872340 (-4125 1625);
PAINT AQUA (-4125 1625);
DISPLAY INVISIBLE (-4125 1625);
FORCEPROP 1 LAST HDL_POWER GND
J 1
(-4175 1550);
DISPLAY 0.872340 (-4175 1550);
PAINT GREEN (-4175 1550);
DISPLAY INVISIBLE (-4175 1550);
FORCEADD Q_CAP..1
(-4200 1825);
FORCEPROP 1 LAST LOCATION C1339
J 0
(-4150 1975);
DISPLAY 0.489362 (-4150 1975);
PAINT SKYBLUE (-4150 1975);
FORCEPROP 0 LAST $SEC 1
J 2
(-4150 2000);
DISPLAY 0.680851 (-4150 2000);
PAINT MONO (-4150 2000);
DISPLAY INVISIBLE (-4150 2000);
FORCEPROP 0 LAST CDS_SEC 1
J 2
(-4150 2000);
DISPLAY 1.021277 (-4150 2000);
DISPLAY INVISIBLE (-4150 2000);
FORCEPROP 1 LASTPIN (-4200 1925) $PN 1
J 0
(-4190 1905);
DISPLAY 0.489362 (-4190 1905);
PAINT MONO (-4190 1905);
FORCEPROP 1 LASTPIN (-4200 1725) $PN 2
J 0
(-4190 1705);
DISPLAY 0.489362 (-4190 1705);
PAINT MONO (-4190 1705);
FORCEPROP 1 LAST VALUE 0.1UF
J 0
(-4150 1925);
DISPLAY 0.489362 (-4150 1925);
PAINT SKYBLUE (-4150 1925);
FORCEPROP 1 LAST PART_NUMBER CH4104K1B00
J 0
(-4150 1675);
DISPLAY 0.489362 (-4150 1675);
PAINT SKYBLUE (-4150 1675);
FORCEPROP 1 LAST MATERIAL X7R
J 0
(-4150 1775);
DISPLAY 0.489362 (-4150 1775);
PAINT SKYBLUE (-4150 1775);
FORCEPROP 1 LAST TOLERANCE 10%
J 0
(-4150 1825);
DISPLAY 0.489362 (-4150 1825);
PAINT SKYBLUE (-4150 1825);
FORCEPROP 1 LAST VOLTAGE 25V
J 0
(-4150 1875);
DISPLAY 0.489362 (-4150 1875);
PAINT SKYBLUE (-4150 1875);
FORCEPROP 1 LAST PACK_TYPE 0402
J 0
(-4150 1725);
DISPLAY 0.489362 (-4150 1725);
PAINT SKYBLUE (-4150 1725);
FORCEPROP 2 LAST CDS_LIB pure_quanta
J 2
(-4200 1825);
DISPLAY INVISIBLE (-4200 1825);
FORCEPROP 1 LAST PATH I66
J 0
(-4150 1975);
DISPLAY 0.978723 (-4150 1975);
PAINT WHITE (-4150 1975);
DISPLAY INVISIBLE (-4150 1975);
FORCEADD UNIVERSAL_POWER..1
R 2
(-4275 2100);
FORCEPROP 3 LASTPIN (-4275 2050) SIG_NAME P3V3_STBY\g
J 0
(-4265 2060);
DISPLAY 0.659574 (-4265 2060);
PAINT MONO (-4265 2060);
DISPLAY INVISIBLE (-4265 2060);
FORCEPROP 1 LAST HDL_POWER P3V3_STBY
J 1
(-4275 2150);
DISPLAY 0.489362 (-4275 2150);
PAINT GREEN (-4275 2150);
FORCEPROP 2 LAST CDS_LIB pure_quanta_power
J 2
(-4275 2100);
DISPLAY INVISIBLE (-4275 2100);
FORCEPROP 1 LAST PATH I67
J 2
(-4325 2125);
DISPLAY 0.872340 (-4325 2125);
PAINT AQUA (-4325 2125);
DISPLAY INVISIBLE (-4325 2125);
FORCEADD PI3CSW12ZUAEX..1
(-4700 1400);
FORCEPROP 1 LAST LOCATION U108
J 0
(-4844 1893);
DISPLAY 0.489362 (-4844 1893);
PAINT SKYBLUE (-4844 1893);
FORCEPROP 0 LAST $SEC 1
J 0
(-4825 2050);
DISPLAY 0.680851 (-4825 2050);
PAINT MONO (-4825 2050);
DISPLAY INVISIBLE (-4825 2050);
FORCEPROP 0 LAST CDS_SEC 1
J 0
(-4825 2050);
DISPLAY 1.021277 (-4825 2050);
DISPLAY INVISIBLE (-4825 2050);
FORCEPROP 0 LASTPIN (-5000 1400) $PN 1
J 2
(-5010 1410);
DISPLAY 0.489362 (-5010 1410);
PAINT MONO (-5010 1410);
FORCEPROP 0 LASTPIN (-5000 1350) $PN 2
J 2
(-5010 1360);
DISPLAY 0.489362 (-5010 1360);
PAINT MONO (-5010 1360);
FORCEPROP 0 LASTPIN (-5000 1300) $PN 3
J 2
(-5010 1310);
DISPLAY 0.489362 (-5010 1310);
PAINT MONO (-5010 1310);
FORCEPROP 0 LASTPIN (-5000 1250) $PN 4
J 2
(-5010 1260);
DISPLAY 0.489362 (-5010 1260);
PAINT MONO (-5010 1260);
FORCEPROP 0 LASTPIN (-4400 1500) $PN 8
J 0
(-4390 1510);
DISPLAY 0.489362 (-4390 1510);
PAINT MONO (-4390 1510);
FORCEPROP 0 LASTPIN (-4400 1450) $PN 7
J 0
(-4390 1460);
DISPLAY 0.489362 (-4390 1460);
PAINT MONO (-4390 1460);
FORCEPROP 0 LASTPIN (-4400 1250) $PN 5
J 0
(-4390 1260);
DISPLAY 0.489362 (-4390 1260);
PAINT MONO (-4390 1260);
FORCEPROP 0 LASTPIN (-5000 1550) $PN 6
J 2
(-5010 1560);
DISPLAY 0.489362 (-5010 1560);
PAINT MONO (-5010 1560);
FORCEPROP 0 LASTPIN (-5000 1500) $PN 9
J 2
(-5010 1510);
DISPLAY 0.489362 (-5010 1510);
PAINT MONO (-5010 1510);
FORCEPROP 0 LASTPIN (-4400 1550) $PN 10
J 0
(-4390 1560);
DISPLAY 0.489362 (-4390 1560);
PAINT MONO (-4390 1560);
FORCEPROP 1 LAST MATERIAL IC
J 0
(-4844 1619);
DISPLAY 0.489362 (-4844 1619);
PAINT SKYBLUE (-4844 1619);
FORCEPROP 2 LAST PART_TYPE SMLF
J 0
(-4825 2000);
DISPLAY 1.021277 (-4825 2000);
FORCEPROP 2 LAST VALUE PI3CSW12ZUAEX
J 0
(-4825 1950);
DISPLAY 0.489362 (-4825 1950);
PAINT SKYBLUE (-4825 1950);
FORCEPROP 1 LAST PART_NUMBER AL3CSW12000
J 0
(-4844 1746);
DISPLAY 0.489362 (-4844 1746);
PAINT SKYBLUE (-4844 1746);
FORCEPROP 1 LAST NEEDS_NO_SIZE TRUE
J 0
(-4700 1400);
DISPLAY 0.723404 (-4700 1400);
PAINT GREEN (-4700 1400);
DISPLAY INVISIBLE (-4700 1400);
FORCEPROP 1 LAST CDS_LMAN_SYM_OUTLINE -150,200,150,-200
J 0
(-4700 1400);
DISPLAY 0.468085 (-4700 1400);
PAINT GREEN (-4700 1400);
DISPLAY INVISIBLE (-4700 1400);
FORCEPROP 2 LAST CDS_LIB pure_quanta
J 0
(-4700 1400);
DISPLAY INVISIBLE (-4700 1400);
FORCEPROP 1 LAST PATH I68
J 0
(-4700 1400);
DISPLAY 0.723404 (-4700 1400);
PAINT GREEN (-4700 1400);
DISPLAY INVISIBLE (-4700 1400);
FORCEADD OFFPAGE..2
(-1825 4475);
FORCEPROP 2 LAST $XR5 96 
J 0
(-1186 4475);
DISPLAY 0.638298 (-1186 4475);
PAINT MONO (-1186 4475);
FORCEPROP 2 LAST $XR4 95 
J 0
(-1276 4475);
DISPLAY 0.638298 (-1276 4475);
PAINT MONO (-1276 4475);
FORCEPROP 2 LAST $XR3 94 
J 0
(-1366 4475);
DISPLAY 0.638298 (-1366 4475);
PAINT MONO (-1366 4475);
FORCEPROP 2 LAST $XR2 93 
J 0
(-1456 4475);
DISPLAY 0.638298 (-1456 4475);
PAINT MONO (-1456 4475);
FORCEPROP 2 LAST $XR1 92 
J 0
(-1546 4475);
DISPLAY 0.638298 (-1546 4475);
PAINT MONO (-1546 4475);
FORCEPROP 2 LAST $XR0 91 
J 0
(-1636 4475);
DISPLAY 0.638298 (-1636 4475);
PAINT MONO (-1636 4475);
FORCEPROP 2 LAST CDS_LIB standard
J 0
(-1825 4475);
DISPLAY INVISIBLE (-1825 4475);
FORCEPROP 1 LAST OFFPAGE TRUE
J 0
(-1500 4350);
DISPLAY 0.872340 (-1500 4350);
PAINT GREEN (-1500 4350);
DISPLAY INVISIBLE (-1500 4350);
FORCEPROP 1 LAST COMMENT_BODY TRUE
J 0
(-1870 4380);
DISPLAY 0.872340 (-1870 4380);
PAINT GREEN (-1870 4380);
DISPLAY INVISIBLE (-1870 4380);
FORCEPROP 2 LAST PATH I69
J 0
(-1625 4525);
DISPLAY 1.021277 (-1625 4525);
DISPLAY INVISIBLE (-1625 4525);
FORCEADD OFFPAGE..3
(-1825 4425);
FORCEPROP 2 LAST $XR5 96 
J 0
(-1161 4425);
DISPLAY 0.638298 (-1161 4425);
PAINT MONO (-1161 4425);
FORCEPROP 2 LAST $XR4 95 
J 0
(-1251 4425);
DISPLAY 0.638298 (-1251 4425);
PAINT MONO (-1251 4425);
FORCEPROP 2 LAST $XR3 94 
J 0
(-1341 4425);
DISPLAY 0.638298 (-1341 4425);
PAINT MONO (-1341 4425);
FORCEPROP 2 LAST $XR2 93 
J 0
(-1431 4425);
DISPLAY 0.638298 (-1431 4425);
PAINT MONO (-1431 4425);
FORCEPROP 2 LAST $XR1 92 
J 0
(-1521 4425);
DISPLAY 0.638298 (-1521 4425);
PAINT MONO (-1521 4425);
FORCEPROP 2 LAST $XR0 91 
J 0
(-1611 4425);
DISPLAY 0.638298 (-1611 4425);
PAINT MONO (-1611 4425);
FORCEPROP 2 LAST CDS_LIB standard
J 0
(-1825 4425);
DISPLAY INVISIBLE (-1825 4425);
FORCEPROP 1 LAST OFFPAGE TRUE
J 0
(-1500 4300);
DISPLAY 0.872340 (-1500 4300);
PAINT GREEN (-1500 4300);
DISPLAY INVISIBLE (-1500 4300);
FORCEPROP 1 LAST COMMENT_BODY TRUE
J 0
(-1875 4325);
DISPLAY 0.872340 (-1875 4325);
PAINT GREEN (-1875 4325);
DISPLAY INVISIBLE (-1875 4325);
FORCEPROP 2 LAST PATH I70
J 0
(-1600 4475);
DISPLAY 1.021277 (-1600 4475);
DISPLAY INVISIBLE (-1600 4475);
FORCEADD OFFPAGE..2
(-1875 2950);
FORCEPROP 2 LAST $XR5 102 
J 0
(-1176 2950);
DISPLAY 0.638298 (-1176 2950);
PAINT MONO (-1176 2950);
FORCEPROP 2 LAST $XR4 101 
J 0
(-1296 2950);
DISPLAY 0.638298 (-1296 2950);
PAINT MONO (-1296 2950);
FORCEPROP 2 LAST $XR3 100 
J 0
(-1416 2950);
DISPLAY 0.638298 (-1416 2950);
PAINT MONO (-1416 2950);
FORCEPROP 2 LAST $XR2 99 
J 0
(-1506 2950);
DISPLAY 0.638298 (-1506 2950);
PAINT MONO (-1506 2950);
FORCEPROP 2 LAST $XR1 98 
J 0
(-1596 2950);
DISPLAY 0.638298 (-1596 2950);
PAINT MONO (-1596 2950);
FORCEPROP 2 LAST $XR0 97 
J 0
(-1686 2950);
DISPLAY 0.638298 (-1686 2950);
PAINT MONO (-1686 2950);
FORCEPROP 2 LAST CDS_LIB standard
J 0
(-1875 2950);
DISPLAY INVISIBLE (-1875 2950);
FORCEPROP 1 LAST OFFPAGE TRUE
J 0
(-1550 2825);
DISPLAY 0.872340 (-1550 2825);
PAINT GREEN (-1550 2825);
DISPLAY INVISIBLE (-1550 2825);
FORCEPROP 1 LAST COMMENT_BODY TRUE
J 0
(-1920 2855);
DISPLAY 0.872340 (-1920 2855);
PAINT GREEN (-1920 2855);
DISPLAY INVISIBLE (-1920 2855);
FORCEPROP 2 LAST PATH I71
J 0
(-1675 3000);
DISPLAY 1.021277 (-1675 3000);
DISPLAY INVISIBLE (-1675 3000);
FORCEADD OFFPAGE..3
(-1875 2900);
FORCEPROP 2 LAST $XR5 102 
J 0
(-1151 2900);
DISPLAY 0.638298 (-1151 2900);
PAINT MONO (-1151 2900);
FORCEPROP 2 LAST $XR4 101 
J 0
(-1271 2900);
DISPLAY 0.638298 (-1271 2900);
PAINT MONO (-1271 2900);
FORCEPROP 2 LAST $XR3 100 
J 0
(-1391 2900);
DISPLAY 0.638298 (-1391 2900);
PAINT MONO (-1391 2900);
FORCEPROP 2 LAST $XR2 99 
J 0
(-1481 2900);
DISPLAY 0.638298 (-1481 2900);
PAINT MONO (-1481 2900);
FORCEPROP 2 LAST $XR1 98 
J 0
(-1571 2900);
DISPLAY 0.638298 (-1571 2900);
PAINT MONO (-1571 2900);
FORCEPROP 2 LAST $XR0 97 
J 0
(-1661 2900);
DISPLAY 0.638298 (-1661 2900);
PAINT MONO (-1661 2900);
FORCEPROP 2 LAST CDS_LIB standard
J 0
(-1875 2900);
DISPLAY INVISIBLE (-1875 2900);
FORCEPROP 1 LAST OFFPAGE TRUE
J 0
(-1550 2775);
DISPLAY 0.872340 (-1550 2775);
PAINT GREEN (-1550 2775);
DISPLAY INVISIBLE (-1550 2775);
FORCEPROP 1 LAST COMMENT_BODY TRUE
J 0
(-1925 2800);
DISPLAY 0.872340 (-1925 2800);
PAINT GREEN (-1925 2800);
DISPLAY INVISIBLE (-1925 2800);
FORCEPROP 2 LAST PATH I72
J 0
(-1650 2950);
DISPLAY 1.021277 (-1650 2950);
DISPLAY INVISIBLE (-1650 2950);
FORCEADD OFFPAGE..2
(-1850 1500);
FORCEPROP 2 LAST $XR5 108 
J 0
(-1061 1500);
DISPLAY 0.638298 (-1061 1500);
PAINT MONO (-1061 1500);
FORCEPROP 2 LAST $XR4 107 
J 0
(-1181 1500);
DISPLAY 0.638298 (-1181 1500);
PAINT MONO (-1181 1500);
FORCEPROP 2 LAST $XR3 106 
J 0
(-1301 1500);
DISPLAY 0.638298 (-1301 1500);
PAINT MONO (-1301 1500);
FORCEPROP 2 LAST $XR2 105 
J 0
(-1421 1500);
DISPLAY 0.638298 (-1421 1500);
PAINT MONO (-1421 1500);
FORCEPROP 2 LAST $XR1 104 
J 0
(-1541 1500);
DISPLAY 0.638298 (-1541 1500);
PAINT MONO (-1541 1500);
FORCEPROP 2 LAST $XR0 103 
J 0
(-1661 1500);
DISPLAY 0.638298 (-1661 1500);
PAINT MONO (-1661 1500);
FORCEPROP 2 LAST CDS_LIB standard
J 0
(-1850 1500);
DISPLAY INVISIBLE (-1850 1500);
FORCEPROP 1 LAST OFFPAGE TRUE
J 0
(-1525 1375);
DISPLAY 0.872340 (-1525 1375);
PAINT GREEN (-1525 1375);
DISPLAY INVISIBLE (-1525 1375);
FORCEPROP 1 LAST COMMENT_BODY TRUE
J 0
(-1895 1405);
DISPLAY 0.872340 (-1895 1405);
PAINT GREEN (-1895 1405);
DISPLAY INVISIBLE (-1895 1405);
FORCEPROP 2 LAST PATH I73
J 0
(-1650 1550);
DISPLAY 1.021277 (-1650 1550);
DISPLAY INVISIBLE (-1650 1550);
FORCEADD OFFPAGE..3
(-1850 1450);
FORCEPROP 2 LAST $XR5 108 
J 0
(-1036 1450);
DISPLAY 0.638298 (-1036 1450);
PAINT MONO (-1036 1450);
FORCEPROP 2 LAST $XR4 107 
J 0
(-1156 1450);
DISPLAY 0.638298 (-1156 1450);
PAINT MONO (-1156 1450);
FORCEPROP 2 LAST $XR3 106 
J 0
(-1276 1450);
DISPLAY 0.638298 (-1276 1450);
PAINT MONO (-1276 1450);
FORCEPROP 2 LAST $XR2 105 
J 0
(-1396 1450);
DISPLAY 0.638298 (-1396 1450);
PAINT MONO (-1396 1450);
FORCEPROP 2 LAST $XR1 104 
J 0
(-1516 1450);
DISPLAY 0.638298 (-1516 1450);
PAINT MONO (-1516 1450);
FORCEPROP 2 LAST $XR0 103 
J 0
(-1636 1450);
DISPLAY 0.638298 (-1636 1450);
PAINT MONO (-1636 1450);
FORCEPROP 2 LAST CDS_LIB standard
J 0
(-1850 1450);
DISPLAY INVISIBLE (-1850 1450);
FORCEPROP 1 LAST OFFPAGE TRUE
J 0
(-1525 1325);
DISPLAY 0.872340 (-1525 1325);
PAINT GREEN (-1525 1325);
DISPLAY INVISIBLE (-1525 1325);
FORCEPROP 1 LAST COMMENT_BODY TRUE
J 0
(-1900 1350);
DISPLAY 0.872340 (-1900 1350);
PAINT GREEN (-1900 1350);
DISPLAY INVISIBLE (-1900 1350);
FORCEPROP 2 LAST PATH I74
J 0
(-1625 1500);
DISPLAY 1.021277 (-1625 1500);
DISPLAY INVISIBLE (-1625 1500);
FORCEADD Q_RES..1
R 2
(-6075 5775);
FORCEPROP 1 LAST LOCATION R426
J 2
(-6175 5775);
DISPLAY 0.489362 (-6175 5775);
PAINT SKYBLUE (-6175 5775);
FORCEPROP 0 LAST $SEC 1
J 2
(-5800 5825);
DISPLAY 0.680851 (-5800 5825);
PAINT MONO (-5800 5825);
DISPLAY INVISIBLE (-5800 5825);
FORCEPROP 0 LAST CDS_SEC 1
J 2
(-5800 5825);
DISPLAY 1.021277 (-5800 5825);
DISPLAY INVISIBLE (-5800 5825);
FORCEPROP 1 LASTPIN (-5975 5775) $PN 1
J 2
(-5987 5787);
DISPLAY 0.489362 (-5987 5787);
PAINT MONO (-5987 5787);
FORCEPROP 1 LASTPIN (-6175 5775) $PN 2
J 2
(-6137 5787);
DISPLAY 0.489362 (-6137 5787);
PAINT MONO (-6137 5787);
FORCEPROP 1 LAST VALUE 0
J 0
(-5975 5775);
DISPLAY 0.489362 (-5975 5775);
PAINT SKYBLUE (-5975 5775);
FORCEPROP 2 LAST CDS_LIB pure_quanta
J 2
(-6075 5775);
DISPLAY INVISIBLE (-6075 5775);
FORCEPROP 1 LAST PATH I99
J 2
(-6025 5925);
DISPLAY 0.978723 (-6025 5925);
PAINT WHITE (-6025 5925);
DISPLAY INVISIBLE (-6025 5925);
FORCEPROP 1 LAST WATTAGE 1/16W
J 0
(-6475 5700);
DISPLAY 0.489362 (-6475 5700);
PAINT SKYBLUE (-6475 5700);
DISPLAY INVISIBLE (-6475 5700);
FORCEPROP 1 LAST MATERIAL CHIP
J 2
(-6500 5700);
DISPLAY 0.489362 (-6500 5700);
PAINT SKYBLUE (-6500 5700);
DISPLAY INVISIBLE (-6500 5700);
FORCEPROP 1 LAST TOLERANCE 5%
J 2
(-6050 5700);
DISPLAY 0.489362 (-6050 5700);
PAINT SKYBLUE (-6050 5700);
DISPLAY INVISIBLE (-6050 5700);
FORCEPROP 1 LAST PART_NUMBER CS00002JB38
J 2
(-6100 5825);
DISPLAY 0.489362 (-6100 5825);
PAINT SKYBLUE (-6100 5825);
DISPLAY INVISIBLE (-6100 5825);
FORCEPROP 1 LAST PACK_TYPE 0402LF
J 2
(-6125 5700);
DISPLAY 0.489362 (-6125 5700);
PAINT SKYBLUE (-6125 5700);
DISPLAY INVISIBLE (-6125 5700);
FORCEADD CAD_NOTE..1
(-6375 5150);
FORCEPROP 0 LAST NOTE CPU I3C BYPASS, RES CO-LAYOUT
J 0
(-6525 4975);
DISPLAY 1.021277 (-6525 4975);
FORCEPROP 2 LAST CDS_LIB pure_quanta_power
J 0
(-6375 5150);
DISPLAY INVISIBLE (-6375 5150);
FORCEPROP 1 LAST COMMENT_BODY TRUE
J 0
(-6350 5250);
DISPLAY 0.978723 (-6350 5250);
DISPLAY INVISIBLE (-6350 5250);
FORCEADD CAD_NOTE..1
(-6300 2250);
FORCEPROP 0 LAST NOTE CPU I3C BYPASS, RES CO-LAYOUT
J 0
(-6450 2075);
DISPLAY 1.021277 (-6450 2075);
FORCEPROP 2 LAST CDS_LIB pure_quanta_power
J 0
(-6300 2250);
DISPLAY INVISIBLE (-6300 2250);
FORCEPROP 1 LAST COMMENT_BODY TRUE
J 0
(-6275 2350);
DISPLAY 0.978723 (-6275 2350);
DISPLAY INVISIBLE (-6275 2350);
FORCEADD DNS..2
(-5875 3925);
PAINT RED (-5875 3925);
FORCEPROP 2 LAST BOM_COST OCP3.0 
J 0
(-6000 4050);
DISPLAY 0.680851 (-6000 4050);
DISPLAY INVISIBLE (-6000 4050);
FORCEPROP 2 LAST CDS_LIB mstr_misc
J 0
(-5875 3925);
DISPLAY INVISIBLE (-5875 3925);
FORCEPROP 1 LAST COMMENT_BODY TRUE
J 0
(-5875 3925);
DISPLAY 0.744681 (-5875 3925);
DISPLAY INVISIBLE (-5875 3925);
FORCEADD DNS..2
(-5825 2400);
PAINT RED (-5825 2400);
FORCEPROP 2 LAST CDS_LIB mstr_misc
J 0
(-5825 2400);
DISPLAY INVISIBLE (-5825 2400);
FORCEPROP 2 LAST BOM_COST OCP3.0 
J 0
(-5950 2525);
DISPLAY 0.680851 (-5950 2525);
DISPLAY INVISIBLE (-5950 2525);
FORCEPROP 1 LAST COMMENT_BODY TRUE
J 0
(-5825 2400);
DISPLAY 0.744681 (-5825 2400);
DISPLAY INVISIBLE (-5825 2400);
FORCEADD DNS..2
(-3000 3900);
PAINT RED (-3000 3900);
FORCEPROP 2 LAST BOM_COST OCP3.0 
J 0
(-3125 4025);
DISPLAY 0.680851 (-3125 4025);
DISPLAY INVISIBLE (-3125 4025);
FORCEPROP 2 LAST CDS_LIB mstr_misc
J 0
(-3000 3900);
DISPLAY INVISIBLE (-3000 3900);
FORCEPROP 1 LAST COMMENT_BODY TRUE
J 0
(-3000 3900);
DISPLAY 0.744681 (-3000 3900);
DISPLAY INVISIBLE (-3000 3900);
FORCEADD CAD_NOTE..1
(-6275 550);
FORCEPROP 0 LAST NOTE CPU I3C BYPASS, RES CO-LAYOUT
J 0
(-6425 375);
DISPLAY 1.021277 (-6425 375);
FORCEPROP 2 LAST CDS_LIB pure_quanta_power
J 0
(-6275 550);
DISPLAY INVISIBLE (-6275 550);
FORCEPROP 1 LAST COMMENT_BODY TRUE
J 0
(-6250 650);
DISPLAY 0.978723 (-6250 650);
DISPLAY INVISIBLE (-6250 650);
FORCEADD DNS..2
(-5775 950);
PAINT RED (-5775 950);
FORCEPROP 2 LAST CDS_LIB mstr_misc
J 0
(-5775 950);
DISPLAY INVISIBLE (-5775 950);
FORCEPROP 2 LAST BOM_COST OCP3.0 
J 0
(-5900 1075);
DISPLAY 0.680851 (-5900 1075);
DISPLAY INVISIBLE (-5900 1075);
FORCEPROP 1 LAST COMMENT_BODY TRUE
J 0
(-5775 950);
DISPLAY 0.744681 (-5775 950);
DISPLAY INVISIBLE (-5775 950);
FORCEADD DNS..2
(-2950 2375);
PAINT RED (-2950 2375);
FORCEPROP 2 LAST CDS_LIB mstr_misc
J 0
(-2950 2375);
DISPLAY INVISIBLE (-2950 2375);
FORCEPROP 2 LAST BOM_COST OCP3.0 
J 0
(-3075 2500);
DISPLAY 0.680851 (-3075 2500);
DISPLAY INVISIBLE (-3075 2500);
FORCEPROP 1 LAST COMMENT_BODY TRUE
J 0
(-2950 2375);
DISPLAY 0.744681 (-2950 2375);
DISPLAY INVISIBLE (-2950 2375);
FORCEADD QUANTA_TITLE_BLOCK_C..1
(0 0);
FORCEPROP 0 LAST CDS_CON_LAST_MODIFIED Fri Mar 11 14:53:13 2022
J 0
(-1885 15);
DISPLAY INVISIBLE (-1885 15);
FORCEPROP 1 LAST CUSTOM_TXT_CDS <CON_LAST_MODIFIED>
J 0
(-1885 15);
DISPLAY 0.978723 (-1885 15);
FORCEPROP 2 LAST CUSTOM_TXT_CDS <XR_PAGE_TITLE>
J 0
(-7890 5250);
DISPLAY 0.638298 (-7890 5250);
PAINT PINK (-7890 5250);
DISPLAY INVISIBLE (-7890 5250);
FORCEPROP 1 LAST CUSTOM_TXT_CDS <NAME_2>
J 0
(-3175 50);
FORCEPROP 1 LAST CUSTOM_TXT_CDS <NAME_1>
J 0
(-3175 175);
FORCEPROP 1 LAST CUSTOM_TXT_CDS <Q_NUMBER>
J 0
(-1403 103);
DISPLAY 1.212766 (-1403 103);
FORCEPROP 1 LAST CUSTOM_TXT_CDS <Q_PROJ>
J 0
(-2382 102);
DISPLAY 1.212766 (-2382 102);
FORCEPROP 1 LAST CUSTOM_TXT_CDS <Q_REV>
J 0
(-184 103);
DISPLAY 1.212766 (-184 103);
FORCEPROP 1 LAST CUSTOM_TXT_CDS <CON_PAGE_NUM> OF <CON_TOTAL_PAGES>
J 0
(-446 18);
DISPLAY 0.978723 (-446 18);
FORCEPROP 1 LAST Q_TITLE I3C MUX - DDR5 SPD
J 0
(-9250 75);
DISPLAY 2.446809 (-9250 75);
PAINT GREEN (-9250 75);
FORCEPROP 1 LAST Q_DEPT BU9
J 1
(-3700 -25);
DISPLAY 1.957447 (-3700 -25);
PAINT GREEN (-3700 -25);
FORCEPROP 2 LAST CDS_LIB pure_quanta
J 0
(0 0);
DISPLAY INVISIBLE (0 0);
FORCEPROP 1 LAST CDS_LMAN_SYM_OUTLINE -9475,6775,100,-125
J 0
(0 0);
DISPLAY 0.468085 (0 0);
PAINT GREEN (0 0);
DISPLAY INVISIBLE (0 0);
FORCEPROP 2 LAST PAGE_BORDER TRUE
J 0
(-7890 5250);
DISPLAY 0.638298 (-7890 5250);
PAINT PINK (-7890 5250);
DISPLAY INVISIBLE (-7890 5250);
FORCEPROP 1 LAST COMMENT_BODY TRUE
J 0
(12 -13);
DISPLAY 0.978723 (12 -13);
PAINT GREEN (12 -13);
DISPLAY INVISIBLE (12 -13);
FORCEPROP 2 LAST CDS_XR_PAGE_TITLE CR-136 : @T6G_MB_LIB.T6G(SCH_1):PAGE136
J 0
(-7890 5250);
DISPLAY 0.638298 (-7890 5250);
PAINT PINK (-7890 5250);
DISPLAY INVISIBLE (-7890 5250);
FORCEADD CAD_NOTE..1
(-6325 3700);
FORCEPROP 0 LAST NOTE CPU I3C BYPASS, RES CO-LAYOUT
J 0
(-6475 3525);
DISPLAY 1.021277 (-6475 3525);
FORCEPROP 2 LAST CDS_LIB pure_quanta_power
J 0
(-6325 3700);
DISPLAY INVISIBLE (-6325 3700);
FORCEPROP 1 LAST COMMENT_BODY TRUE
J 0
(-6300 3800);
DISPLAY 0.978723 (-6300 3800);
DISPLAY INVISIBLE (-6300 3800);
FORCEADD DNS..2
(-3050 5300);
PAINT RED (-3050 5300);
FORCEPROP 2 LAST CDS_LIB mstr_misc
J 0
(-3050 5300);
DISPLAY INVISIBLE (-3050 5300);
FORCEPROP 2 LAST BOM_COST OCP3.0 
J 0
(-3175 5425);
DISPLAY 0.680851 (-3175 5425);
DISPLAY INVISIBLE (-3175 5425);
FORCEPROP 1 LAST COMMENT_BODY TRUE
J 0
(-3050 5300);
DISPLAY 0.744681 (-3050 5300);
DISPLAY INVISIBLE (-3050 5300);
FORCEADD DNS..2
(-2900 925);
PAINT RED (-2900 925);
FORCEPROP 2 LAST BOM_COST OCP3.0 
J 0
(-3025 1050);
DISPLAY 0.680851 (-3025 1050);
DISPLAY INVISIBLE (-3025 1050);
FORCEPROP 1 LAST COMMENT_BODY TRUE
J 0
(-2900 925);
DISPLAY 0.744681 (-2900 925);
DISPLAY INVISIBLE (-2900 925);
FORCEPROP 2 LAST CDS_LIB mstr_misc
J 0
(-2900 925);
DISPLAY INVISIBLE (-2900 925);
FORCEADD DNS..2
(-5625 6175);
PAINT RED (-5625 6175);
FORCEPROP 2 LAST BOM_COST OCP3.0 
J 0
(-5750 6300);
DISPLAY 0.680851 (-5750 6300);
DISPLAY INVISIBLE (-5750 6300);
FORCEPROP 1 LAST COMMENT_BODY TRUE
J 0
(-5625 6175);
DISPLAY 0.744681 (-5625 6175);
DISPLAY INVISIBLE (-5625 6175);
FORCEPROP 2 LAST CDS_LIB mstr_misc
J 0
(-5625 6175);
DISPLAY INVISIBLE (-5625 6175);
FORCEADD DNS..2
(-5425 6175);
PAINT RED (-5425 6175);
FORCEPROP 1 LAST COMMENT_BODY TRUE
J 0
(-5425 6175);
DISPLAY 0.744681 (-5425 6175);
DISPLAY INVISIBLE (-5425 6175);
FORCEPROP 2 LAST BOM_COST OCP3.0 
J 0
(-5550 6300);
DISPLAY 0.680851 (-5550 6300);
DISPLAY INVISIBLE (-5550 6300);
FORCEPROP 2 LAST CDS_LIB mstr_misc
J 0
(-5425 6175);
DISPLAY INVISIBLE (-5425 6175);
FORCEADD DNS..2
(-5650 4675);
PAINT RED (-5650 4675);
FORCEPROP 1 LAST COMMENT_BODY TRUE
J 0
(-5650 4675);
DISPLAY 0.744681 (-5650 4675);
DISPLAY INVISIBLE (-5650 4675);
FORCEPROP 2 LAST BOM_COST OCP3.0 
J 0
(-5775 4800);
DISPLAY 0.680851 (-5775 4800);
DISPLAY INVISIBLE (-5775 4800);
FORCEPROP 2 LAST CDS_LIB mstr_misc
J 0
(-5650 4675);
DISPLAY INVISIBLE (-5650 4675);
FORCEADD DNS..2
(-5450 4675);
PAINT RED (-5450 4675);
FORCEPROP 1 LAST COMMENT_BODY TRUE
J 0
(-5450 4675);
DISPLAY 0.744681 (-5450 4675);
DISPLAY INVISIBLE (-5450 4675);
FORCEPROP 2 LAST BOM_COST OCP3.0 
J 0
(-5575 4800);
DISPLAY 0.680851 (-5575 4800);
DISPLAY INVISIBLE (-5575 4800);
FORCEPROP 2 LAST CDS_LIB mstr_misc
J 0
(-5450 4675);
DISPLAY INVISIBLE (-5450 4675);
FORCEADD DNS..2
(-5625 3175);
PAINT RED (-5625 3175);
FORCEPROP 1 LAST COMMENT_BODY TRUE
J 0
(-5625 3175);
DISPLAY 0.744681 (-5625 3175);
DISPLAY INVISIBLE (-5625 3175);
FORCEPROP 2 LAST BOM_COST OCP3.0 
J 0
(-5750 3300);
DISPLAY 0.680851 (-5750 3300);
DISPLAY INVISIBLE (-5750 3300);
FORCEPROP 2 LAST CDS_LIB mstr_misc
J 0
(-5625 3175);
DISPLAY INVISIBLE (-5625 3175);
FORCEADD DNS..2
(-5425 3175);
PAINT RED (-5425 3175);
FORCEPROP 1 LAST COMMENT_BODY TRUE
J 0
(-5425 3175);
DISPLAY 0.744681 (-5425 3175);
DISPLAY INVISIBLE (-5425 3175);
FORCEPROP 2 LAST BOM_COST OCP3.0 
J 0
(-5550 3300);
DISPLAY 0.680851 (-5550 3300);
DISPLAY INVISIBLE (-5550 3300);
FORCEPROP 2 LAST CDS_LIB mstr_misc
J 0
(-5425 3175);
DISPLAY INVISIBLE (-5425 3175);
FORCEADD DNS..2
(-5625 1725);
PAINT RED (-5625 1725);
FORCEPROP 1 LAST COMMENT_BODY TRUE
J 0
(-5625 1725);
DISPLAY 0.744681 (-5625 1725);
DISPLAY INVISIBLE (-5625 1725);
FORCEPROP 2 LAST BOM_COST OCP3.0 
J 0
(-5750 1850);
DISPLAY 0.680851 (-5750 1850);
DISPLAY INVISIBLE (-5750 1850);
FORCEPROP 2 LAST CDS_LIB mstr_misc
J 0
(-5625 1725);
DISPLAY INVISIBLE (-5625 1725);
FORCEADD DNS..2
(-5425 1725);
PAINT RED (-5425 1725);
FORCEPROP 1 LAST COMMENT_BODY TRUE
J 0
(-5425 1725);
DISPLAY 0.744681 (-5425 1725);
DISPLAY INVISIBLE (-5425 1725);
FORCEPROP 2 LAST BOM_COST OCP3.0 
J 0
(-5550 1850);
DISPLAY 0.680851 (-5550 1850);
DISPLAY INVISIBLE (-5550 1850);
FORCEPROP 2 LAST CDS_LIB mstr_misc
J 0
(-5425 1725);
DISPLAY INVISIBLE (-5425 1725);
FORCEADD DNS..2
(-5925 5325);
PAINT RED (-5925 5325);
FORCEPROP 2 LAST CDS_LIB mstr_misc
J 0
(-5925 5325);
DISPLAY INVISIBLE (-5925 5325);
FORCEPROP 1 LAST COMMENT_BODY TRUE
J 0
(-5925 5325);
DISPLAY 0.744681 (-5925 5325);
DISPLAY INVISIBLE (-5925 5325);
FORCEPROP 2 LAST BOM_COST OCP3.0 
J 0
(-6050 5450);
DISPLAY 0.680851 (-6050 5450);
DISPLAY INVISIBLE (-6050 5450);
WIRE 16 -1 (-4325 5625)(-4325 5500);
WIRE 16 -1 (-4475 5625)(-4325 5625);
WIRE 16 -1 (-4275 6100)(-4275 6050);
WIRE 16 -1 (-4250 4700)(-4250 4650);
WIRE 16 -1 (-4300 4225)(-4300 4100);
WIRE 16 -1 (-4450 4225)(-4300 4225);
WIRE 16 -1 (-4300 2700)(-4300 2575);
WIRE 16 -1 (-4450 2700)(-4300 2700);
WIRE 16 -1 (-4250 3175)(-4250 3125);
WIRE 16 -1 (-4250 1250)(-4250 1125);
WIRE 16 -1 (-4400 1250)(-4250 1250);
WIRE 16 -1 (-4200 1725)(-4200 1675);
WIRE 16 -1 (-5975 5625)(-5650 5625);
FORCEPROP 2 LAST SIG_NAME I3C_SCM_0_R_SDA
J 0
(-5925 5635);
DISPLAY 0.489362 (-5925 5635);
WIRE 16 -1 (-5075 5625)(-5650 5625);
WIRE 16 -1 (-5650 6075)(-5650 5625);
WIRE 16 -1 (-6000 5325)(-3275 5325);
FORCEPROP 2 LAST SIG_NAME I3C_SPD_DDRAF_CPU0_BYPASS_SCL
J 0
(-5050 5335);
DISPLAY 0.489362 (-5050 5335);
FORCEPROP 2 LASTPROP $XRERR UNIQUE?
J 0
(-5290 5335);
DISPLAY 0.638298 (-5290 5335);
PAINT MONO (-5290 5335);
DISPLAY INVISIBLE (-5290 5335);
WIRE 16 -1 (-4350 6375)(-4350 5925);
WIRE 16 -1 (-4350 6425)(-4350 6375);
WIRE 16 -1 (-4275 6375)(-4350 6375);
WIRE 16 -1 (-4350 5925)(-4475 5925);
WIRE 16 -1 (-4275 6300)(-4275 6375);
WIRE 16 -1 (-5975 5675)(-5450 5675);
FORCEPROP 2 LAST SIG_NAME I3C_SCM_0_R_SCL
J 0
(-5925 5685);
DISPLAY 0.489362 (-5925 5685);
WIRE 16 -1 (-5450 5675)(-5075 5675);
WIRE 16 -1 (-5450 5675)(-5450 6075);
WIRE 16 -1 (-5900 4525)(-5050 4525);
FORCEPROP 2 LAST SIG_NAME FM_I3C_CPU0_MUX1_OE_N
J 0
(-5710 4535);
DISPLAY 0.489362 (-5710 4535);
WIRE 16 -1 (-4325 4975)(-4325 4525);
WIRE 16 -1 (-4325 5025)(-4325 4975);
WIRE 16 -1 (-4250 4975)(-4325 4975);
WIRE 16 -1 (-4325 4525)(-4450 4525);
WIRE 16 -1 (-4250 4900)(-4250 4975);
WIRE 16 -1 (-4325 3450)(-4325 3000);
WIRE 16 -1 (-4325 3500)(-4325 3450);
WIRE 16 -1 (-4250 3450)(-4325 3450);
WIRE 16 -1 (-4325 3000)(-4450 3000);
WIRE 16 -1 (-4250 3375)(-4250 3450);
WIRE 16 -1 (-5900 3000)(-5050 3000);
FORCEPROP 2 LAST SIG_NAME FM_I3C_CPU1_MUX0_OE_N
J 0
(-5710 3010);
DISPLAY 0.489362 (-5710 3010);
WIRE 16 -1 (-5900 2950)(-5050 2950);
FORCEPROP 2 LAST SIG_NAME FM_I3C_CPU1_MUX0_SEL
J 0
(-5710 2960);
DISPLAY 0.489362 (-5710 2960);
WIRE 16 -1 (-3175 2350)(-5900 2350);
FORCEPROP 2 LAST SIG_NAME I3C_SPD_DDRAF_CPU1_BYPASS_SDA
J 0
(-4950 2360);
DISPLAY 0.489362 (-4950 2360);
FORCEPROP 2 LASTPROP $XRERR UNIQUE?
J 0
(-5190 2360);
DISPLAY 0.638298 (-5190 2360);
PAINT MONO (-5190 2360);
DISPLAY INVISIBLE (-5190 2360);
WIRE 16 -1 (-4275 2000)(-4275 1550);
WIRE 16 -1 (-4275 2050)(-4275 2000);
WIRE 16 -1 (-4200 2000)(-4275 2000);
WIRE 16 -1 (-4275 1550)(-4400 1550);
WIRE 16 -1 (-4200 1925)(-4200 2000);
WIRE 16 -1 (-5850 1550)(-5000 1550);
FORCEPROP 2 LAST SIG_NAME FM_I3C_CPU1_MUX1_OE_N
J 0
(-5660 1560);
DISPLAY 0.489362 (-5660 1560);
WIRE 16 -1 (-5850 1500)(-5000 1500);
FORCEPROP 2 LAST SIG_NAME FM_I3C_CPU1_MUX1_SEL
J 0
(-5660 1510);
DISPLAY 0.489362 (-5660 1510);
WIRE 16 -1 (-5000 1400)(-5875 1400);
FORCEPROP 2 LAST SIG_NAME I3C_1_SPD_DDRGL_CPU1_SCL
J 0
(-5825 1410);
DISPLAY 0.489362 (-5825 1410);
FORCEPROP 2 LASTPROP $XRERR UNIQUE?
J 0
(-6065 1410);
DISPLAY 0.638298 (-6065 1410);
PAINT MONO (-6065 1410);
DISPLAY INVISIBLE (-6065 1410);
WIRE 16 -1 (-5000 1350)(-5875 1350);
FORCEPROP 2 LAST SIG_NAME I3C_1_SPD_DDRGL_CPU1_SDA
J 0
(-5825 1360);
DISPLAY 0.489362 (-5825 1360);
FORCEPROP 2 LASTPROP $XRERR UNIQUE?
J 0
(-6065 1360);
DISPLAY 0.638298 (-6065 1360);
PAINT MONO (-6065 1360);
DISPLAY INVISIBLE (-6065 1360);
WIRE 16 -1 (-5875 1300)(-5450 1300);
FORCEPROP 2 LAST SIG_NAME I3C_SCM_3_R_SCL
J 0
(-5825 1310);
DISPLAY 0.489362 (-5825 1310);
WIRE 16 -1 (-5450 1300)(-5000 1300);
WIRE 16 -1 (-5450 1300)(-5450 1625);
WIRE 16 -1 (-5950 2750)(-5450 2750);
FORCEPROP 2 LAST SIG_NAME I3C_SCM_2_R_SCL
J 0
(-5910 2760);
DISPLAY 0.489362 (-5910 2760);
WIRE 16 -1 (-5450 2750)(-5050 2750);
WIRE 16 -1 (-5450 2750)(-5450 3075);
WIRE 16 -1 (-6425 5775)(-6425 5325);
WIRE 16 -1 (-6175 5775)(-6425 5775);
WIRE 16 -1 (-6425 5775)(-7075 5775);
FORCEPROP 2 LAST SIG_NAME I3C_0_SPD_DDRAF_CPU0_R_SCL
J 2
(-6485 5785);
DISPLAY 0.489362 (-6485 5785);
WIRE 16 -1 (-6425 5325)(-6200 5325);
WIRE 16 -1 (-6475 5725)(-6475 5275);
WIRE 16 -1 (-6175 5725)(-6475 5725);
WIRE 16 -1 (-6475 5725)(-7075 5725);
FORCEPROP 2 LAST SIG_NAME I3C_0_SPD_DDRAF_CPU0_R_SDA
J 2
(-6485 5735);
DISPLAY 0.489362 (-6485 5735);
WIRE 16 -1 (-6475 5275)(-6200 5275);
WIRE 16 -1 (-5925 5925)(-5075 5925);
FORCEPROP 2 LAST SIG_NAME FM_I3C_CPU0_MUX0_OE_N
J 0
(-5735 5935);
DISPLAY 0.489362 (-5735 5935);
WIRE 16 -1 (-5925 5875)(-5075 5875);
FORCEPROP 2 LAST SIG_NAME FM_I3C_CPU0_MUX0_SEL
J 0
(-5735 5885);
DISPLAY 0.489362 (-5735 5885);
WIRE 16 -1 (-5075 5775)(-5975 5775);
FORCEPROP 2 LAST SIG_NAME I3C_0_SPD_DDRAF_CPU0_SCL
J 0
(-5925 5785);
DISPLAY 0.489362 (-5925 5785);
FORCEPROP 2 LASTPROP $XRERR UNIQUE?
J 0
(-6165 5785);
DISPLAY 0.638298 (-6165 5785);
PAINT MONO (-6165 5785);
DISPLAY INVISIBLE (-6165 5785);
WIRE 16 -1 (-5075 5725)(-5975 5725);
FORCEPROP 2 LAST SIG_NAME I3C_0_SPD_DDRAF_CPU0_SDA
J 0
(-5925 5735);
DISPLAY 0.489362 (-5925 5735);
FORCEPROP 2 LASTPROP $XRERR UNIQUE?
J 0
(-6165 5735);
DISPLAY 0.638298 (-6165 5735);
PAINT MONO (-6165 5735);
DISPLAY INVISIBLE (-6165 5735);
WIRE 16 -1 (-2825 5825)(-2825 5275);
WIRE 16 -1 (-1875 5825)(-2825 5825);
FORCEPROP 2 LAST SIG_NAME I3C_SPD_DDRAF_CPU0_SDA
J 2
(-1925 5835);
DISPLAY 0.489362 (-1925 5835);
WIRE 16 -1 (-2825 5825)(-3050 5825);
WIRE 16 -1 (-2825 5275)(-3075 5275);
WIRE 16 -1 (-1875 5875)(-2900 5875);
FORCEPROP 2 LAST SIG_NAME I3C_SPD_DDRAF_CPU0_SCL
J 2
(-1925 5885);
DISPLAY 0.489362 (-1925 5885);
WIRE 16 -1 (-2900 5875)(-3050 5875);
WIRE 16 -1 (-2900 5325)(-2900 5875);
WIRE 16 -1 (-2900 5325)(-3075 5325);
WIRE 16 -1 (-4475 5875)(-3450 5875);
FORCEPROP 2 LAST SIG_NAME I3C_SPD_DDRAF_CPU0_LVC1_SCL
J 2
(-3525 5885);
DISPLAY 0.489362 (-3525 5885);
FORCEPROP 2 LASTPROP $XRERR UNIQUE?
J 0
(-3765 5885);
DISPLAY 0.638298 (-3765 5885);
PAINT MONO (-3765 5885);
DISPLAY INVISIBLE (-3765 5885);
WIRE 16 -1 (-3450 5875)(-3250 5875);
WIRE 16 -1 (-3450 5875)(-3450 6000);
WIRE 16 -1 (-3450 6275)(-3450 6325);
WIRE 16 -1 (-3450 6200)(-3450 6275);
WIRE 16 -1 (-3650 6275)(-3450 6275);
WIRE 16 -1 (-3650 6275)(-3650 6200);
WIRE 16 -1 (-3450 1900)(-3450 1950);
WIRE 16 -1 (-3450 1825)(-3450 1900);
WIRE 16 -1 (-3650 1900)(-3450 1900);
WIRE 16 -1 (-3650 1900)(-3650 1825);
WIRE 16 -1 (-4450 2950)(-3450 2950);
FORCEPROP 2 LAST SIG_NAME I3C_SPD_DDRAF_CPU1_LVC1_SCL
J 2
(-3525 2960);
DISPLAY 0.489362 (-3525 2960);
FORCEPROP 2 LASTPROP $XRERR UNIQUE?
J 0
(-3765 2960);
DISPLAY 0.638298 (-3765 2960);
PAINT MONO (-3765 2960);
DISPLAY INVISIBLE (-3765 2960);
WIRE 16 -1 (-3450 2950)(-3450 3075);
WIRE 16 -1 (-3450 2950)(-3300 2950);
WIRE 16 -1 (-4475 5825)(-3650 5825);
WIRE 16 -1 (-3650 5825)(-3250 5825);
FORCEPROP 2 LAST SIG_NAME I3C_SPD_DDRAF_CPU0_LVC1_SDA
J 2
(-3525 5835);
DISPLAY 0.489362 (-3525 5835);
FORCEPROP 2 LASTPROP $XRERR UNIQUE?
J 0
(-3765 5835);
DISPLAY 0.638298 (-3765 5835);
PAINT MONO (-3765 5835);
DISPLAY INVISIBLE (-3765 5835);
WIRE 16 -1 (-3650 6000)(-3650 5825);
WIRE 16 -1 (-5900 2400)(-3175 2400);
FORCEPROP 2 LAST SIG_NAME I3C_SPD_DDRAF_CPU1_BYPASS_SCL
J 0
(-4950 2410);
DISPLAY 0.489362 (-4950 2410);
FORCEPROP 2 LASTPROP $XRERR UNIQUE?
J 0
(-5190 2410);
DISPLAY 0.638298 (-5190 2410);
PAINT MONO (-5190 2410);
DISPLAY INVISIBLE (-5190 2410);
WIRE 16 -1 (-5450 1850)(-5450 1875);
WIRE 16 -1 (-5450 1825)(-5450 1850);
WIRE 16 -1 (-5650 1850)(-5450 1850);
WIRE 16 -1 (-5650 1850)(-5650 1825);
WIRE 16 -1 (-5450 3300)(-5450 3325);
WIRE 16 -1 (-5450 3275)(-5450 3300);
WIRE 16 -1 (-5650 3300)(-5450 3300);
WIRE 16 -1 (-5650 3300)(-5650 3275);
WIRE 16 -1 (-5450 4825)(-5450 4850);
WIRE 16 -1 (-5450 4800)(-5450 4825);
WIRE 16 -1 (-5650 4825)(-5450 4825);
WIRE 16 -1 (-5650 4825)(-5650 4800);
WIRE 16 -1 (-5450 6375)(-5450 6425);
WIRE 16 -1 (-5450 6275)(-5450 6375);
WIRE 16 -1 (-5650 6375)(-5450 6375);
WIRE 16 -1 (-5650 6375)(-5650 6275);
WIRE 16 -1 (-3450 3350)(-3450 3400);
WIRE 16 -1 (-3450 3275)(-3450 3350);
WIRE 16 -1 (-3650 3350)(-3450 3350);
WIRE 16 -1 (-3650 3350)(-3650 3275);
WIRE 16 -1 (-3450 4875)(-3650 4875);
WIRE 16 -1 (-3450 4925)(-3450 4875);
WIRE 16 -1 (-3450 4875)(-3450 4800);
WIRE 16 -1 (-3650 4875)(-3650 4800);
WIRE 16 -1 (-3450 1500)(-3450 1625);
WIRE 16 -1 (-3450 1500)(-3275 1500);
WIRE 16 -1 (-4400 1500)(-3450 1500);
FORCEPROP 2 LAST SIG_NAME I3C_SPD_DDRGL_CPU1_LVC1_SCL
J 2
(-3500 1510);
DISPLAY 0.489362 (-3500 1510);
FORCEPROP 2 LASTPROP $XRERR UNIQUE?
J 0
(-3740 1510);
DISPLAY 0.638298 (-3740 1510);
PAINT MONO (-3740 1510);
DISPLAY INVISIBLE (-3740 1510);
WIRE 16 -1 (-5950 3925)(-3225 3925);
FORCEPROP 2 LAST SIG_NAME I3C_SPD_DDRGL_CPU0_BYPASS_SCL
J 0
(-5000 3935);
DISPLAY 0.489362 (-5000 3935);
FORCEPROP 2 LASTPROP $XRERR UNIQUE?
J 0
(-5240 3935);
DISPLAY 0.638298 (-5240 3935);
PAINT MONO (-5240 3935);
DISPLAY INVISIBLE (-5240 3935);
WIRE 16 -1 (-2750 950)(-2750 1500);
WIRE 16 -1 (-2750 950)(-2925 950);
WIRE 16 -1 (-1900 1500)(-2750 1500);
FORCEPROP 2 LAST SIG_NAME I3C_SPD_DDRGL_CPU1_SCL
J 2
(-1925 1510);
DISPLAY 0.489362 (-1925 1510);
WIRE 16 -1 (-2750 1500)(-3075 1500);
WIRE 16 -1 (-3275 5275)(-6000 5275);
FORCEPROP 2 LAST SIG_NAME I3C_SPD_DDRAF_CPU0_BYPASS_SDA
J 0
(-5050 5285);
DISPLAY 0.489362 (-5050 5285);
FORCEPROP 2 LASTPROP $XRERR UNIQUE?
J 0
(-5290 5285);
DISPLAY 0.638298 (-5290 5285);
PAINT MONO (-5290 5285);
DISPLAY INVISIBLE (-5290 5285);
WIRE 16 -1 (-2775 4425)(-2775 3875);
WIRE 16 -1 (-1875 4425)(-2775 4425);
FORCEPROP 2 LAST SIG_NAME I3C_SPD_DDRGL_CPU0_SDA
J 2
(-1925 4435);
DISPLAY 0.489362 (-1925 4435);
WIRE 16 -1 (-2775 4425)(-3050 4425);
WIRE 16 -1 (-2775 3875)(-3025 3875);
WIRE 16 -1 (-4450 2900)(-3650 2900);
WIRE 16 -1 (-3650 3075)(-3650 2900);
WIRE 16 -1 (-3650 2900)(-3300 2900);
FORCEPROP 2 LAST SIG_NAME I3C_SPD_DDRAF_CPU1_LVC1_SDA
J 2
(-3525 2910);
DISPLAY 0.489362 (-3525 2910);
FORCEPROP 2 LASTPROP $XRERR UNIQUE?
J 0
(-3765 2910);
DISPLAY 0.638298 (-3765 2910);
PAINT MONO (-3765 2910);
DISPLAY INVISIBLE (-3765 2910);
WIRE 16 -1 (-6325 900)(-6050 900);
WIRE 16 -1 (-6325 1350)(-6325 900);
WIRE 16 -1 (-6075 1350)(-6325 1350);
FORCEPROP 2 LAST SIG_NAME I3C_1_SPD_DDRGL_CPU1_R_SDA
J 2
(-6310 1360);
DISPLAY 0.489362 (-6310 1360);
WIRE 16 -1 (-6325 1350)(-6975 1350);
WIRE 16 -1 (-6275 950)(-6050 950);
WIRE 16 -1 (-6275 1400)(-6275 950);
WIRE 16 -1 (-6075 1400)(-6275 1400);
WIRE 16 -1 (-6275 1400)(-6975 1400);
FORCEPROP 2 LAST SIG_NAME I3C_1_SPD_DDRGL_CPU1_R_SCL
J 2
(-6310 1410);
DISPLAY 0.489362 (-6310 1410);
WIRE 16 -1 (-6325 2400)(-6100 2400);
WIRE 16 -1 (-6325 2850)(-6325 2400);
WIRE 16 -1 (-6150 2850)(-6325 2850);
WIRE 16 -1 (-6325 2850)(-7050 2850);
FORCEPROP 2 LAST SIG_NAME I3C_0_SPD_DDRAF_CPU1_R_SCL
J 2
(-6385 2860);
DISPLAY 0.489362 (-6385 2860);
WIRE 16 -1 (-6375 2350)(-6100 2350);
WIRE 16 -1 (-6375 2800)(-6375 2350);
WIRE 16 -1 (-6150 2800)(-6375 2800);
WIRE 16 -1 (-6375 2800)(-7050 2800);
FORCEPROP 2 LAST SIG_NAME I3C_0_SPD_DDRAF_CPU1_R_SDA
J 2
(-6385 2810);
DISPLAY 0.489362 (-6385 2810);
WIRE 16 -1 (-5050 4325)(-5950 4325);
FORCEPROP 2 LAST SIG_NAME I3C_1_SPD_DDRGL_CPU0_SDA
J 0
(-5900 4335);
DISPLAY 0.489362 (-5900 4335);
FORCEPROP 2 LASTPROP $XRERR UNIQUE?
J 0
(-6140 4335);
DISPLAY 0.638298 (-6140 4335);
PAINT MONO (-6140 4335);
DISPLAY INVISIBLE (-6140 4335);
WIRE 16 -1 (-5650 3075)(-5650 2700);
WIRE 16 -1 (-5650 2700)(-5050 2700);
WIRE 16 -1 (-5950 2700)(-5650 2700);
FORCEPROP 2 LAST SIG_NAME I3C_SCM_2_R_SDA
J 0
(-5910 2710);
DISPLAY 0.489362 (-5910 2710);
WIRE 16 -1 (-5650 1625)(-5650 1250);
WIRE 16 -1 (-5650 1250)(-5000 1250);
WIRE 16 -1 (-5875 1250)(-5650 1250);
FORCEPROP 2 LAST SIG_NAME I3C_SCM_3_R_SDA
J 0
(-5825 1260);
DISPLAY 0.489362 (-5825 1260);
WIRE 16 -1 (-5650 4600)(-5650 4225);
WIRE 16 -1 (-5650 4225)(-5050 4225);
WIRE 16 -1 (-5950 4225)(-5650 4225);
FORCEPROP 2 LAST SIG_NAME I3C_SCM_1_R_SDA
J 0
(-5900 4235);
DISPLAY 0.489362 (-5900 4235);
WIRE 16 -1 (-5450 4275)(-5050 4275);
WIRE 16 -1 (-5450 4275)(-5450 4600);
WIRE 16 -1 (-5950 4275)(-5450 4275);
FORCEPROP 2 LAST SIG_NAME I3C_SCM_1_R_SCL
J 0
(-5900 4285);
DISPLAY 0.489362 (-5900 4285);
WIRE 16 -1 (-5050 2800)(-5950 2800);
FORCEPROP 2 LAST SIG_NAME I3C_0_SPD_DDRAF_CPU1_SDA
J 0
(-5910 2810);
DISPLAY 0.489362 (-5910 2810);
FORCEPROP 2 LASTPROP $XRERR UNIQUE?
J 0
(-6150 2810);
DISPLAY 0.638298 (-6150 2810);
PAINT MONO (-6150 2810);
DISPLAY INVISIBLE (-6150 2810);
WIRE 16 -1 (-5050 2850)(-5950 2850);
FORCEPROP 2 LAST SIG_NAME I3C_0_SPD_DDRAF_CPU1_SCL
J 0
(-5910 2860);
DISPLAY 0.489362 (-5910 2860);
FORCEPROP 2 LASTPROP $XRERR UNIQUE?
J 0
(-6150 2860);
DISPLAY 0.638298 (-6150 2860);
PAINT MONO (-6150 2860);
DISPLAY INVISIBLE (-6150 2860);
WIRE 16 -1 (-5900 4475)(-5050 4475);
FORCEPROP 2 LAST SIG_NAME FM_I3C_CPU0_MUX1_SEL
J 0
(-5710 4485);
DISPLAY 0.489362 (-5710 4485);
WIRE 16 -1 (-5050 4375)(-5950 4375);
FORCEPROP 2 LAST SIG_NAME I3C_1_SPD_DDRGL_CPU0_SCL
J 0
(-5900 4385);
DISPLAY 0.489362 (-5900 4385);
FORCEPROP 2 LASTPROP $XRERR UNIQUE?
J 0
(-6140 4385);
DISPLAY 0.638298 (-6140 4385);
PAINT MONO (-6140 4385);
DISPLAY INVISIBLE (-6140 4385);
WIRE 16 -1 (-3225 3875)(-5950 3875);
FORCEPROP 2 LAST SIG_NAME I3C_SPD_DDRGL_CPU0_BYPASS_SDA
J 0
(-5000 3885);
DISPLAY 0.489362 (-5000 3885);
FORCEPROP 2 LASTPROP $XRERR UNIQUE?
J 0
(-5240 3885);
DISPLAY 0.638298 (-5240 3885);
PAINT MONO (-5240 3885);
DISPLAY INVISIBLE (-5240 3885);
WIRE 16 -1 (-4400 1450)(-3650 1450);
WIRE 16 -1 (-3650 1450)(-3275 1450);
FORCEPROP 2 LAST SIG_NAME I3C_SPD_DDRGL_CPU1_LVC1_SDA
J 2
(-3500 1460);
DISPLAY 0.489362 (-3500 1460);
FORCEPROP 2 LASTPROP $XRERR UNIQUE?
J 0
(-3740 1460);
DISPLAY 0.638298 (-3740 1460);
PAINT MONO (-3740 1460);
DISPLAY INVISIBLE (-3740 1460);
WIRE 16 -1 (-3650 1625)(-3650 1450);
WIRE 16 -1 (-2800 2400)(-2800 2950);
WIRE 16 -1 (-2800 2400)(-2975 2400);
WIRE 16 -1 (-1925 2950)(-2800 2950);
FORCEPROP 2 LAST SIG_NAME I3C_SPD_DDRAF_CPU1_SCL
J 2
(-1925 2960);
DISPLAY 0.489362 (-1925 2960);
WIRE 16 -1 (-2800 2950)(-3100 2950);
WIRE 16 -1 (-2725 2900)(-2725 2350);
WIRE 16 -1 (-1925 2900)(-2725 2900);
FORCEPROP 2 LAST SIG_NAME I3C_SPD_DDRAF_CPU1_SDA
J 2
(-1925 2910);
DISPLAY 0.489362 (-1925 2910);
WIRE 16 -1 (-2725 2900)(-3100 2900);
WIRE 16 -1 (-2725 2350)(-2975 2350);
WIRE 16 -1 (-2850 3925)(-2850 4475);
WIRE 16 -1 (-2850 3925)(-3025 3925);
WIRE 16 -1 (-1875 4475)(-2850 4475);
FORCEPROP 2 LAST SIG_NAME I3C_SPD_DDRGL_CPU0_SCL
J 2
(-1925 4485);
DISPLAY 0.489362 (-1925 4485);
WIRE 16 -1 (-2850 4475)(-3050 4475);
WIRE 16 -1 (-5850 950)(-3125 950);
FORCEPROP 2 LAST SIG_NAME I3C_SPD_DDRGL_CPU1_BYPASS_SCL
J 0
(-4900 960);
DISPLAY 0.489362 (-4900 960);
FORCEPROP 2 LASTPROP $XRERR UNIQUE?
J 0
(-5140 960);
DISPLAY 0.638298 (-5140 960);
PAINT MONO (-5140 960);
DISPLAY INVISIBLE (-5140 960);
WIRE 16 -1 (-3125 900)(-5850 900);
FORCEPROP 2 LAST SIG_NAME I3C_SPD_DDRGL_CPU1_BYPASS_SDA
J 0
(-4900 910);
DISPLAY 0.489362 (-4900 910);
FORCEPROP 2 LASTPROP $XRERR UNIQUE?
J 0
(-5140 910);
DISPLAY 0.638298 (-5140 910);
PAINT MONO (-5140 910);
DISPLAY INVISIBLE (-5140 910);
WIRE 16 -1 (-6425 4325)(-6425 3875);
WIRE 16 -1 (-6150 4325)(-6425 4325);
WIRE 16 -1 (-6425 4325)(-7050 4325);
FORCEPROP 2 LAST SIG_NAME I3C_1_SPD_DDRGL_CPU0_R_SDA
J 2
(-6460 4335);
DISPLAY 0.489362 (-6460 4335);
WIRE 16 -1 (-6425 3875)(-6150 3875);
WIRE 16 -1 (-6375 4375)(-6375 3925);
WIRE 16 -1 (-6150 4375)(-6375 4375);
WIRE 16 -1 (-6375 4375)(-7050 4375);
FORCEPROP 2 LAST SIG_NAME I3C_1_SPD_DDRGL_CPU0_R_SCL
J 2
(-6460 4385);
DISPLAY 0.489362 (-6460 4385);
WIRE 16 -1 (-6375 3925)(-6150 3925);
WIRE 16 -1 (-2675 1450)(-2675 900);
WIRE 16 -1 (-1900 1450)(-2675 1450);
FORCEPROP 2 LAST SIG_NAME I3C_SPD_DDRGL_CPU1_SDA
J 2
(-1925 1460);
DISPLAY 0.489362 (-1925 1460);
WIRE 16 -1 (-2675 1450)(-3075 1450);
WIRE 16 -1 (-2675 900)(-2925 900);
WIRE 16 -1 (-4450 4425)(-3650 4425);
WIRE 16 -1 (-3650 4425)(-3250 4425);
FORCEPROP 2 LAST SIG_NAME I3C_SPD_DDRGL_CPU0_LVC1_SDA
J 2
(-3525 4435);
DISPLAY 0.489362 (-3525 4435);
FORCEPROP 2 LASTPROP $XRERR UNIQUE?
J 0
(-3765 4435);
DISPLAY 0.638298 (-3765 4435);
PAINT MONO (-3765 4435);
DISPLAY INVISIBLE (-3765 4435);
WIRE 16 -1 (-3650 4600)(-3650 4425);
WIRE 16 -1 (-3450 4475)(-3250 4475);
WIRE 16 -1 (-3450 4475)(-3450 4600);
WIRE 16 -1 (-4450 4475)(-3450 4475);
FORCEPROP 2 LAST SIG_NAME I3C_SPD_DDRGL_CPU0_LVC1_SCL
J 2
(-3525 4485);
DISPLAY 0.489362 (-3525 4485);
FORCEPROP 2 LASTPROP $XRERR UNIQUE?
J 0
(-3765 4485);
DISPLAY 0.638298 (-3765 4485);
PAINT MONO (-3765 4485);
DISPLAY INVISIBLE (-3765 4485);
DOT 1 (-6275 1400);
DOT 1 (-6425 5775);
DOT 1 (-6325 1350);
DOT 1 (-6325 2850);
DOT 1 (-4275 2000);
DOT 1 (-6425 4325);
DOT 1 (-6375 4375);
DOT 1 (-2750 1500);
DOT 1 (-2675 1450);
DOT 1 (-2800 2950);
DOT 1 (-2725 2900);
DOT 1 (-2850 4475);
DOT 1 (-2775 4425);
DOT 1 (-2825 5825);
DOT 1 (-6475 5725);
DOT 1 (-4350 6375);
DOT 1 (-3450 5875);
DOT 1 (-4325 4975);
DOT 1 (-3450 4875);
DOT 1 (-3650 4425);
DOT 1 (-3450 4475);
DOT 1 (-3650 2900);
DOT 1 (-3450 3350);
DOT 1 (-3450 1500);
DOT 1 (-3650 1450);
DOT 1 (-3450 2950);
DOT 1 (-5450 5675);
DOT 1 (-5650 5625);
DOT 1 (-5450 6375);
DOT 1 (-5650 4225);
DOT 1 (-5450 4275);
DOT 1 (-5450 4825);
DOT 1 (-5450 2750);
DOT 1 (-5650 2700);
DOT 1 (-5450 3300);
DOT 1 (-5450 1850);
DOT 1 (-5450 1300);
DOT 1 (-5650 1250);
DOT 1 (-6375 2800);
DOT 1 (-3650 5825);
DOT 1 (-3450 6275);
DOT 1 (-3450 1900);
DOT 1 (-2900 5875);
DOT 1 (-4325 3450);
FORCENOTE
$CDS_IMAGE|12312312.jpg|1924|507
(-8150 675) 0;
DISPLAY LEFT (-8150 675);
QUIT
